(kicad_sch
	(version 20250114)
	(generator "eeschema")
	(generator_version "9.0")
	(paper "A3")
	(title_block
		(title "LPDDR4 Test Board")
		(date "2024-02-12")
		(rev "1.1.5")
	)
	(text "DDR4 SODIMM connector"
		(exclude_from_sim no)
		(at 18.415 24.13 0)
		(effects
			(font
				(size 2.9972 2.9972)
				(thickness 0.5994)
				(bold yes)
			)
			(justify left bottom)
		)
	)
	(text "Mechanical protection"
		(exclude_from_sim no)
		(at 24.13 230.505 0)
		(effects
			(font
				(size 2.0066 2.0066)
				(thickness 0.4013)
				(bold yes)
			)
			(justify left bottom)
		)
	)
	(junction
		(at 205.74 71.12)
		(diameter 0)
		(color 0 0 0 0)
	)
	(junction
		(at 287.655 118.745)
		(diameter 0)
		(color 0 0 0 0)
	)
	(junction
		(at 249.555 202.565)
		(diameter 0)
		(color 0 0 0 0)
	)
	(junction
		(at 205.74 68.58)
		(diameter 0)
		(color 0 0 0 0)
	)
	(junction
		(at 213.36 210.82)
		(diameter 0)
		(color 0 0 0 0)
	)
	(junction
		(at 205.74 60.96)
		(diameter 0)
		(color 0 0 0 0)
	)
	(junction
		(at 171.45 111.76)
		(diameter 0)
		(color 0 0 0 0)
	)
	(junction
		(at 163.83 167.64)
		(diameter 0)
		(color 0 0 0 0)
	)
	(junction
		(at 171.45 106.68)
		(diameter 0)
		(color 0 0 0 0)
	)
	(junction
		(at 171.45 99.06)
		(diameter 0)
		(color 0 0 0 0)
	)
	(junction
		(at 205.74 86.36)
		(diameter 0)
		(color 0 0 0 0)
	)
	(junction
		(at 205.74 93.98)
		(diameter 0)
		(color 0 0 0 0)
	)
	(junction
		(at 171.45 78.74)
		(diameter 0)
		(color 0 0 0 0)
	)
	(junction
		(at 249.555 205.105)
		(diameter 0)
		(color 0 0 0 0)
	)
	(junction
		(at 249.555 200.025)
		(diameter 0)
		(color 0 0 0 0)
	)
	(junction
		(at 171.45 86.36)
		(diameter 0)
		(color 0 0 0 0)
	)
	(junction
		(at 171.45 76.2)
		(diameter 0)
		(color 0 0 0 0)
	)
	(junction
		(at 171.45 96.52)
		(diameter 0)
		(color 0 0 0 0)
	)
	(junction
		(at 171.45 104.14)
		(diameter 0)
		(color 0 0 0 0)
	)
	(junction
		(at 171.45 83.82)
		(diameter 0)
		(color 0 0 0 0)
	)
	(junction
		(at 205.74 66.04)
		(diameter 0)
		(color 0 0 0 0)
	)
	(junction
		(at 213.36 208.28)
		(diameter 0)
		(color 0 0 0 0)
	)
	(junction
		(at 254 111.125)
		(diameter 0)
		(color 0 0 0 0)
	)
	(junction
		(at 205.74 109.22)
		(diameter 0)
		(color 0 0 0 0)
	)
	(junction
		(at 171.45 66.04)
		(diameter 0)
		(color 0 0 0 0)
	)
	(junction
		(at 299.085 205.105)
		(diameter 0)
		(color 0 0 0 0)
	)
	(junction
		(at 205.74 88.9)
		(diameter 0)
		(color 0 0 0 0)
	)
	(junction
		(at 163.83 180.34)
		(diameter 0)
		(color 0 0 0 0)
	)
	(junction
		(at 213.36 195.58)
		(diameter 0)
		(color 0 0 0 0)
	)
	(junction
		(at 163.83 175.26)
		(diameter 0)
		(color 0 0 0 0)
	)
	(junction
		(at 171.45 73.66)
		(diameter 0)
		(color 0 0 0 0)
	)
	(junction
		(at 205.74 55.88)
		(diameter 0)
		(color 0 0 0 0)
	)
	(junction
		(at 163.83 177.8)
		(diameter 0)
		(color 0 0 0 0)
	)
	(junction
		(at 205.74 53.34)
		(diameter 0)
		(color 0 0 0 0)
	)
	(junction
		(at 249.555 197.485)
		(diameter 0)
		(color 0 0 0 0)
	)
	(junction
		(at 171.45 109.22)
		(diameter 0)
		(color 0 0 0 0)
	)
	(junction
		(at 171.45 81.28)
		(diameter 0)
		(color 0 0 0 0)
	)
	(junction
		(at 171.45 91.44)
		(diameter 0)
		(color 0 0 0 0)
	)
	(junction
		(at 205.74 76.2)
		(diameter 0)
		(color 0 0 0 0)
	)
	(junction
		(at 205.74 83.82)
		(diameter 0)
		(color 0 0 0 0)
	)
	(junction
		(at 163.83 170.18)
		(diameter 0)
		(color 0 0 0 0)
	)
	(junction
		(at 299.085 207.645)
		(diameter 0)
		(color 0 0 0 0)
	)
	(junction
		(at 171.45 68.58)
		(diameter 0)
		(color 0 0 0 0)
	)
	(junction
		(at 287.655 98.425)
		(diameter 0)
		(color 0 0 0 0)
	)
	(junction
		(at 205.74 78.74)
		(diameter 0)
		(color 0 0 0 0)
	)
	(junction
		(at 171.45 63.5)
		(diameter 0)
		(color 0 0 0 0)
	)
	(junction
		(at 205.74 104.14)
		(diameter 0)
		(color 0 0 0 0)
	)
	(junction
		(at 213.36 200.66)
		(diameter 0)
		(color 0 0 0 0)
	)
	(junction
		(at 205.74 106.68)
		(diameter 0)
		(color 0 0 0 0)
	)
	(junction
		(at 171.45 101.6)
		(diameter 0)
		(color 0 0 0 0)
	)
	(junction
		(at 205.74 111.76)
		(diameter 0)
		(color 0 0 0 0)
	)
	(junction
		(at 171.45 71.12)
		(diameter 0)
		(color 0 0 0 0)
	)
	(junction
		(at 205.74 73.66)
		(diameter 0)
		(color 0 0 0 0)
	)
	(junction
		(at 299.085 210.185)
		(diameter 0)
		(color 0 0 0 0)
	)
	(junction
		(at 205.74 91.44)
		(diameter 0)
		(color 0 0 0 0)
	)
	(junction
		(at 254 154.305)
		(diameter 0)
		(color 0 0 0 0)
	)
	(junction
		(at 171.45 58.42)
		(diameter 0)
		(color 0 0 0 0)
	)
	(junction
		(at 205.74 63.5)
		(diameter 0)
		(color 0 0 0 0)
	)
	(junction
		(at 299.085 212.725)
		(diameter 0)
		(color 0 0 0 0)
	)
	(junction
		(at 171.45 60.96)
		(diameter 0)
		(color 0 0 0 0)
	)
	(junction
		(at 163.83 172.72)
		(diameter 0)
		(color 0 0 0 0)
	)
	(junction
		(at 205.74 81.28)
		(diameter 0)
		(color 0 0 0 0)
	)
	(junction
		(at 163.83 182.88)
		(diameter 0)
		(color 0 0 0 0)
	)
	(junction
		(at 171.45 88.9)
		(diameter 0)
		(color 0 0 0 0)
	)
	(junction
		(at 249.555 212.725)
		(diameter 0)
		(color 0 0 0 0)
	)
	(junction
		(at 205.74 101.6)
		(diameter 0)
		(color 0 0 0 0)
	)
	(junction
		(at 205.74 99.06)
		(diameter 0)
		(color 0 0 0 0)
	)
	(junction
		(at 249.555 207.645)
		(diameter 0)
		(color 0 0 0 0)
	)
	(junction
		(at 171.45 53.34)
		(diameter 0)
		(color 0 0 0 0)
	)
	(junction
		(at 213.36 203.2)
		(diameter 0)
		(color 0 0 0 0)
	)
	(junction
		(at 171.45 55.88)
		(diameter 0)
		(color 0 0 0 0)
	)
	(junction
		(at 299.085 197.485)
		(diameter 0)
		(color 0 0 0 0)
	)
	(junction
		(at 287.655 151.765)
		(diameter 0)
		(color 0 0 0 0)
	)
	(junction
		(at 287.655 139.065)
		(diameter 0)
		(color 0 0 0 0)
	)
	(junction
		(at 205.74 58.42)
		(diameter 0)
		(color 0 0 0 0)
	)
	(junction
		(at 249.555 210.185)
		(diameter 0)
		(color 0 0 0 0)
	)
	(junction
		(at 171.45 93.98)
		(diameter 0)
		(color 0 0 0 0)
	)
	(junction
		(at 213.36 198.12)
		(diameter 0)
		(color 0 0 0 0)
	)
	(junction
		(at 299.085 200.025)
		(diameter 0)
		(color 0 0 0 0)
	)
	(junction
		(at 205.74 96.52)
		(diameter 0)
		(color 0 0 0 0)
	)
	(junction
		(at 254 133.985)
		(diameter 0)
		(color 0 0 0 0)
	)
	(no_connect
		(at 177.165 129.54)
	)
	(no_connect
		(at 262.89 172.085)
	)
	(no_connect
		(at 177.165 205.74)
	)
	(no_connect
		(at 262.89 161.925)
	)
	(no_connect
		(at 285.75 156.845)
	)
	(no_connect
		(at 177.165 121.92)
	)
	(no_connect
		(at 262.89 187.325)
	)
	(no_connect
		(at 200.025 116.84)
	)
	(no_connect
		(at 285.75 65.405)
	)
	(no_connect
		(at 200.025 152.4)
	)
	(no_connect
		(at 285.75 194.945)
	)
	(no_connect
		(at 200.025 139.7)
	)
	(no_connect
		(at 177.165 134.62)
	)
	(no_connect
		(at 200.025 180.34)
	)
	(no_connect
		(at 285.75 73.025)
	)
	(no_connect
		(at 177.165 132.08)
	)
	(no_connect
		(at 262.89 78.105)
	)
	(no_connect
		(at 262.89 174.625)
	)
	(no_connect
		(at 200.025 157.48)
	)
	(no_connect
		(at 262.89 73.025)
	)
	(no_connect
		(at 285.75 70.485)
	)
	(no_connect
		(at 177.165 124.46)
	)
	(no_connect
		(at 285.75 55.245)
	)
	(no_connect
		(at 200.025 137.16)
	)
	(no_connect
		(at 200.025 160.02)
	)
	(no_connect
		(at 262.89 182.245)
	)
	(no_connect
		(at 200.025 177.8)
	)
	(no_connect
		(at 285.75 172.085)
	)
	(no_connect
		(at 285.75 161.925)
	)
	(no_connect
		(at 285.75 192.405)
	)
	(no_connect
		(at 262.89 70.485)
	)
	(no_connect
		(at 262.89 75.565)
	)
	(no_connect
		(at 177.165 190.5)
	)
	(no_connect
		(at 200.025 167.64)
	)
	(no_connect
		(at 285.75 60.325)
	)
	(no_connect
		(at 200.025 144.78)
	)
	(no_connect
		(at 177.165 152.4)
	)
	(no_connect
		(at 262.89 167.005)
	)
	(no_connect
		(at 200.025 162.56)
	)
	(no_connect
		(at 177.165 127)
	)
	(no_connect
		(at 200.025 187.96)
	)
	(no_connect
		(at 285.75 78.105)
	)
	(no_connect
		(at 177.165 149.86)
	)
	(no_connect
		(at 177.165 165.1)
	)
	(no_connect
		(at 177.165 144.78)
	)
	(no_connect
		(at 200.025 129.54)
	)
	(no_connect
		(at 177.165 198.12)
	)
	(no_connect
		(at 285.75 179.705)
	)
	(no_connect
		(at 285.75 52.705)
	)
	(no_connect
		(at 262.89 192.405)
	)
	(no_connect
		(at 200.025 149.86)
	)
	(no_connect
		(at 200.025 193.04)
	)
	(no_connect
		(at 262.89 179.705)
	)
	(no_connect
		(at 200.025 172.72)
	)
	(no_connect
		(at 262.89 177.165)
	)
	(no_connect
		(at 200.025 124.46)
	)
	(no_connect
		(at 262.89 83.185)
	)
	(no_connect
		(at 177.165 119.38)
	)
	(no_connect
		(at 177.165 203.2)
	)
	(no_connect
		(at 200.025 119.38)
	)
	(no_connect
		(at 177.165 139.7)
	)
	(no_connect
		(at 177.165 162.56)
	)
	(no_connect
		(at 177.165 114.3)
	)
	(no_connect
		(at 200.025 121.92)
	)
	(no_connect
		(at 285.75 177.165)
	)
	(no_connect
		(at 285.75 159.385)
	)
	(no_connect
		(at 200.025 127)
	)
	(no_connect
		(at 285.75 57.785)
	)
	(no_connect
		(at 177.165 137.16)
	)
	(no_connect
		(at 200.025 142.24)
	)
	(no_connect
		(at 177.165 116.84)
	)
	(no_connect
		(at 33.02 240.665)
	)
	(no_connect
		(at 200.025 185.42)
	)
	(no_connect
		(at 200.025 190.5)
	)
	(no_connect
		(at 177.165 154.94)
	)
	(no_connect
		(at 285.75 62.865)
	)
	(no_connect
		(at 285.75 167.005)
	)
	(no_connect
		(at 262.89 156.845)
	)
	(no_connect
		(at 262.89 80.645)
	)
	(no_connect
		(at 200.025 175.26)
	)
	(no_connect
		(at 200.025 132.08)
	)
	(no_connect
		(at 285.75 182.245)
	)
	(no_connect
		(at 177.165 208.28)
	)
	(no_connect
		(at 177.165 142.24)
	)
	(no_connect
		(at 262.89 189.865)
	)
	(no_connect
		(at 177.165 160.02)
	)
	(no_connect
		(at 177.165 187.96)
	)
	(no_connect
		(at 200.025 170.18)
	)
	(no_connect
		(at 262.89 164.465)
	)
	(no_connect
		(at 285.75 189.865)
	)
	(no_connect
		(at 285.75 75.565)
	)
	(no_connect
		(at 285.75 164.465)
	)
	(no_connect
		(at 177.165 193.04)
	)
	(no_connect
		(at 200.025 114.3)
	)
	(no_connect
		(at 262.89 85.725)
	)
	(no_connect
		(at 262.89 169.545)
	)
	(no_connect
		(at 285.75 184.785)
	)
	(no_connect
		(at 262.89 184.785)
	)
	(no_connect
		(at 177.165 195.58)
	)
	(no_connect
		(at 262.89 194.945)
	)
	(no_connect
		(at 285.75 174.625)
	)
	(no_connect
		(at 285.75 187.325)
	)
	(no_connect
		(at 285.75 154.305)
	)
	(no_connect
		(at 200.025 147.32)
	)
	(no_connect
		(at 200.025 182.88)
	)
	(no_connect
		(at 177.165 157.48)
	)
	(no_connect
		(at 262.89 88.265)
	)
	(no_connect
		(at 285.75 141.605)
	)
	(no_connect
		(at 285.75 123.825)
	)
	(no_connect
		(at 285.75 126.365)
	)
	(no_connect
		(at 177.165 200.66)
	)
	(no_connect
		(at 285.75 67.945)
	)
	(no_connect
		(at 200.025 154.94)
	)
	(no_connect
		(at 200.025 134.62)
	)
	(no_connect
		(at 262.89 159.385)
	)
	(no_connect
		(at 177.165 147.32)
	)
	(no_connect
		(at 285.75 169.545)
	)
	(no_connect
		(at 200.025 165.1)
	)
	(wire
		(pts
			(xy 171.45 111.76) (xy 171.45 112.395)
		)
		(stroke
			(width 0)
			(type default)
		)
	)
	(wire
		(pts
			(xy 205.74 93.98) (xy 200.025 93.98)
		)
		(stroke
			(width 0)
			(type default)
		)
	)
	(wire
		(pts
			(xy 163.83 182.88) (xy 163.83 185.42)
		)
		(stroke
			(width 0)
			(type default)
		)
	)
	(wire
		(pts
			(xy 177.165 88.9) (xy 171.45 88.9)
		)
		(stroke
			(width 0)
			(type default)
		)
	)
	(wire
		(pts
			(xy 163.83 177.8) (xy 163.83 180.34)
		)
		(stroke
			(width 0)
			(type default)
		)
	)
	(wire
		(pts
			(xy 285.75 144.145) (xy 295.91 144.145)
		)
		(stroke
			(width 0)
			(type default)
		)
	)
	(wire
		(pts
			(xy 163.83 175.26) (xy 177.165 175.26)
		)
		(stroke
			(width 0)
			(type default)
		)
	)
	(wire
		(pts
			(xy 200.025 208.28) (xy 213.36 208.28)
		)
		(stroke
			(width 0)
			(type default)
		)
	)
	(wire
		(pts
			(xy 200.025 63.5) (xy 205.74 63.5)
		)
		(stroke
			(width 0)
			(type default)
		)
	)
	(wire
		(pts
			(xy 205.74 88.9) (xy 205.74 91.44)
		)
		(stroke
			(width 0)
			(type default)
		)
	)
	(wire
		(pts
			(xy 200.025 210.82) (xy 213.36 210.82)
		)
		(stroke
			(width 0)
			(type default)
		)
	)
	(wire
		(pts
			(xy 285.75 103.505) (xy 295.91 103.505)
		)
		(stroke
			(width 0)
			(type default)
		)
	)
	(wire
		(pts
			(xy 262.89 212.725) (xy 249.555 212.725)
		)
		(stroke
			(width 0)
			(type default)
		)
	)
	(wire
		(pts
			(xy 205.74 99.06) (xy 200.025 99.06)
		)
		(stroke
			(width 0)
			(type default)
		)
	)
	(wire
		(pts
			(xy 250.19 126.365) (xy 262.89 126.365)
		)
		(stroke
			(width 0)
			(type default)
		)
	)
	(wire
		(pts
			(xy 205.74 60.96) (xy 205.74 63.5)
		)
		(stroke
			(width 0)
			(type default)
		)
	)
	(wire
		(pts
			(xy 250.19 106.045) (xy 262.89 106.045)
		)
		(stroke
			(width 0)
			(type default)
		)
	)
	(wire
		(pts
			(xy 285.75 210.185) (xy 299.085 210.185)
		)
		(stroke
			(width 0)
			(type default)
		)
	)
	(wire
		(pts
			(xy 205.74 68.58) (xy 205.74 71.12)
		)
		(stroke
			(width 0)
			(type default)
		)
	)
	(wire
		(pts
			(xy 177.165 60.96) (xy 171.45 60.96)
		)
		(stroke
			(width 0)
			(type default)
		)
	)
	(wire
		(pts
			(xy 177.165 99.06) (xy 171.45 99.06)
		)
		(stroke
			(width 0)
			(type default)
		)
	)
	(wire
		(pts
			(xy 213.36 198.12) (xy 213.36 200.66)
		)
		(stroke
			(width 0)
			(type default)
		)
	)
	(wire
		(pts
			(xy 299.085 205.105) (xy 301.625 205.105)
		)
		(stroke
			(width 0)
			(type default)
		)
	)
	(wire
		(pts
			(xy 205.74 55.88) (xy 205.74 58.42)
		)
		(stroke
			(width 0)
			(type default)
		)
	)
	(wire
		(pts
			(xy 285.75 80.645) (xy 287.655 80.645)
		)
		(stroke
			(width 0)
			(type default)
		)
	)
	(wire
		(pts
			(xy 200.025 81.28) (xy 205.74 81.28)
		)
		(stroke
			(width 0)
			(type default)
		)
	)
	(wire
		(pts
			(xy 262.89 93.345) (xy 250.825 93.345)
		)
		(stroke
			(width 0)
			(type default)
		)
	)
	(wire
		(pts
			(xy 254 90.805) (xy 254 111.125)
		)
		(stroke
			(width 0)
			(type default)
		)
	)
	(wire
		(pts
			(xy 249.555 200.025) (xy 249.555 202.565)
		)
		(stroke
			(width 0)
			(type default)
		)
	)
	(wire
		(pts
			(xy 200.025 111.76) (xy 205.74 111.76)
		)
		(stroke
			(width 0)
			(type default)
		)
	)
	(wire
		(pts
			(xy 171.45 99.06) (xy 171.45 101.6)
		)
		(stroke
			(width 0)
			(type default)
		)
	)
	(wire
		(pts
			(xy 177.165 182.88) (xy 163.83 182.88)
		)
		(stroke
			(width 0)
			(type default)
		)
	)
	(wire
		(pts
			(xy 177.165 55.88) (xy 171.45 55.88)
		)
		(stroke
			(width 0)
			(type default)
		)
	)
	(wire
		(pts
			(xy 171.45 68.58) (xy 171.45 71.12)
		)
		(stroke
			(width 0)
			(type default)
		)
	)
	(wire
		(pts
			(xy 163.83 175.26) (xy 163.83 177.8)
		)
		(stroke
			(width 0)
			(type default)
		)
	)
	(wire
		(pts
			(xy 295.91 93.345) (xy 285.75 93.345)
		)
		(stroke
			(width 0)
			(type default)
		)
	)
	(wire
		(pts
			(xy 171.45 60.96) (xy 171.45 63.5)
		)
		(stroke
			(width 0)
			(type default)
		)
	)
	(wire
		(pts
			(xy 177.165 68.58) (xy 171.45 68.58)
		)
		(stroke
			(width 0)
			(type default)
		)
	)
	(wire
		(pts
			(xy 285.75 151.765) (xy 287.655 151.765)
		)
		(stroke
			(width 0)
			(type default)
		)
	)
	(wire
		(pts
			(xy 171.45 93.98) (xy 171.45 96.52)
		)
		(stroke
			(width 0)
			(type default)
		)
	)
	(wire
		(pts
			(xy 255.905 55.245) (xy 262.89 55.245)
		)
		(stroke
			(width 0)
			(type default)
		)
	)
	(wire
		(pts
			(xy 249.555 202.565) (xy 249.555 205.105)
		)
		(stroke
			(width 0)
			(type default)
		)
	)
	(wire
		(pts
			(xy 285.75 116.205) (xy 295.91 116.205)
		)
		(stroke
			(width 0)
			(type default)
		)
	)
	(wire
		(pts
			(xy 200.025 50.8) (xy 205.74 50.8)
		)
		(stroke
			(width 0)
			(type default)
		)
	)
	(wire
		(pts
			(xy 249.555 144.145) (xy 262.89 144.145)
		)
		(stroke
			(width 0)
			(type default)
		)
	)
	(wire
		(pts
			(xy 177.165 185.42) (xy 163.83 185.42)
		)
		(stroke
			(width 0)
			(type default)
		)
	)
	(wire
		(pts
			(xy 205.74 99.06) (xy 205.74 101.6)
		)
		(stroke
			(width 0)
			(type default)
		)
	)
	(wire
		(pts
			(xy 171.45 63.5) (xy 171.45 66.04)
		)
		(stroke
			(width 0)
			(type default)
		)
	)
	(wire
		(pts
			(xy 205.74 76.2) (xy 200.025 76.2)
		)
		(stroke
			(width 0)
			(type default)
		)
	)
	(wire
		(pts
			(xy 249.555 212.725) (xy 249.555 215.265)
		)
		(stroke
			(width 0)
			(type default)
		)
	)
	(wire
		(pts
			(xy 177.165 50.8) (xy 171.45 50.8)
		)
		(stroke
			(width 0)
			(type default)
		)
	)
	(wire
		(pts
			(xy 287.655 98.425) (xy 287.655 118.745)
		)
		(stroke
			(width 0)
			(type default)
		)
	)
	(wire
		(pts
			(xy 249.555 149.225) (xy 262.89 149.225)
		)
		(stroke
			(width 0)
			(type default)
		)
	)
	(wire
		(pts
			(xy 213.36 195.58) (xy 213.36 198.12)
		)
		(stroke
			(width 0)
			(type default)
		)
	)
	(wire
		(pts
			(xy 171.45 104.14) (xy 171.45 106.68)
		)
		(stroke
			(width 0)
			(type default)
		)
	)
	(wire
		(pts
			(xy 287.655 80.645) (xy 287.655 98.425)
		)
		(stroke
			(width 0)
			(type default)
		)
	)
	(wire
		(pts
			(xy 215.9 208.28) (xy 213.36 208.28)
		)
		(stroke
			(width 0)
			(type default)
		)
	)
	(wire
		(pts
			(xy 171.45 78.74) (xy 171.45 81.28)
		)
		(stroke
			(width 0)
			(type default)
		)
	)
	(wire
		(pts
			(xy 285.75 146.685) (xy 295.91 146.685)
		)
		(stroke
			(width 0)
			(type default)
		)
	)
	(wire
		(pts
			(xy 255.905 60.325) (xy 262.89 60.325)
		)
		(stroke
			(width 0)
			(type default)
		)
	)
	(wire
		(pts
			(xy 200.025 66.04) (xy 205.74 66.04)
		)
		(stroke
			(width 0)
			(type default)
		)
	)
	(wire
		(pts
			(xy 287.655 139.065) (xy 287.655 151.765)
		)
		(stroke
			(width 0)
			(type default)
		)
	)
	(wire
		(pts
			(xy 262.89 200.025) (xy 249.555 200.025)
		)
		(stroke
			(width 0)
			(type default)
		)
	)
	(wire
		(pts
			(xy 177.165 81.28) (xy 171.45 81.28)
		)
		(stroke
			(width 0)
			(type default)
		)
	)
	(wire
		(pts
			(xy 171.45 55.88) (xy 171.45 58.42)
		)
		(stroke
			(width 0)
			(type default)
		)
	)
	(wire
		(pts
			(xy 299.085 212.725) (xy 299.085 215.265)
		)
		(stroke
			(width 0)
			(type default)
		)
	)
	(wire
		(pts
			(xy 247.015 197.485) (xy 249.555 197.485)
		)
		(stroke
			(width 0)
			(type default)
		)
	)
	(wire
		(pts
			(xy 200.025 78.74) (xy 205.74 78.74)
		)
		(stroke
			(width 0)
			(type default)
		)
	)
	(wire
		(pts
			(xy 177.165 96.52) (xy 171.45 96.52)
		)
		(stroke
			(width 0)
			(type default)
		)
	)
	(wire
		(pts
			(xy 262.89 210.185) (xy 249.555 210.185)
		)
		(stroke
			(width 0)
			(type default)
		)
	)
	(wire
		(pts
			(xy 200.025 101.6) (xy 205.74 101.6)
		)
		(stroke
			(width 0)
			(type default)
		)
	)
	(wire
		(pts
			(xy 205.74 91.44) (xy 205.74 93.98)
		)
		(stroke
			(width 0)
			(type default)
		)
	)
	(wire
		(pts
			(xy 299.085 197.485) (xy 299.085 200.025)
		)
		(stroke
			(width 0)
			(type default)
		)
	)
	(wire
		(pts
			(xy 202.565 218.44) (xy 202.565 220.98)
		)
		(stroke
			(width 0)
			(type default)
		)
	)
	(wire
		(pts
			(xy 205.74 53.34) (xy 200.025 53.34)
		)
		(stroke
			(width 0)
			(type default)
		)
	)
	(wire
		(pts
			(xy 205.74 60.96) (xy 200.025 60.96)
		)
		(stroke
			(width 0)
			(type default)
		)
	)
	(wire
		(pts
			(xy 205.74 86.36) (xy 205.74 88.9)
		)
		(stroke
			(width 0)
			(type default)
		)
	)
	(wire
		(pts
			(xy 285.75 215.265) (xy 299.085 215.265)
		)
		(stroke
			(width 0)
			(type default)
		)
	)
	(wire
		(pts
			(xy 200.025 96.52) (xy 205.74 96.52)
		)
		(stroke
			(width 0)
			(type default)
		)
	)
	(wire
		(pts
			(xy 254 133.985) (xy 262.89 133.985)
		)
		(stroke
			(width 0)
			(type default)
		)
	)
	(wire
		(pts
			(xy 177.165 106.68) (xy 171.45 106.68)
		)
		(stroke
			(width 0)
			(type default)
		)
	)
	(wire
		(pts
			(xy 250.19 113.665) (xy 262.89 113.665)
		)
		(stroke
			(width 0)
			(type default)
		)
	)
	(wire
		(pts
			(xy 171.45 101.6) (xy 171.45 104.14)
		)
		(stroke
			(width 0)
			(type default)
		)
	)
	(wire
		(pts
			(xy 205.74 106.68) (xy 205.74 109.22)
		)
		(stroke
			(width 0)
			(type default)
		)
	)
	(wire
		(pts
			(xy 205.74 96.52) (xy 205.74 99.06)
		)
		(stroke
			(width 0)
			(type default)
		)
	)
	(wire
		(pts
			(xy 177.165 213.36) (xy 170.18 213.36)
		)
		(stroke
			(width 0)
			(type default)
		)
	)
	(wire
		(pts
			(xy 285.75 118.745) (xy 287.655 118.745)
		)
		(stroke
			(width 0)
			(type default)
		)
	)
	(wire
		(pts
			(xy 163.83 170.18) (xy 163.83 172.72)
		)
		(stroke
			(width 0)
			(type default)
		)
	)
	(wire
		(pts
			(xy 205.74 101.6) (xy 205.74 104.14)
		)
		(stroke
			(width 0)
			(type default)
		)
	)
	(wire
		(pts
			(xy 255.905 57.785) (xy 262.89 57.785)
		)
		(stroke
			(width 0)
			(type default)
		)
	)
	(wire
		(pts
			(xy 299.085 205.105) (xy 299.085 207.645)
		)
		(stroke
			(width 0)
			(type default)
		)
	)
	(wire
		(pts
			(xy 287.655 151.765) (xy 287.655 217.805)
		)
		(stroke
			(width 0)
			(type default)
		)
	)
	(wire
		(pts
			(xy 285.75 205.105) (xy 299.085 205.105)
		)
		(stroke
			(width 0)
			(type default)
		)
	)
	(wire
		(pts
			(xy 200.025 198.12) (xy 213.36 198.12)
		)
		(stroke
			(width 0)
			(type default)
		)
	)
	(wire
		(pts
			(xy 250.19 118.745) (xy 262.89 118.745)
		)
		(stroke
			(width 0)
			(type default)
		)
	)
	(wire
		(pts
			(xy 295.91 90.805) (xy 285.75 90.805)
		)
		(stroke
			(width 0)
			(type default)
		)
	)
	(wire
		(pts
			(xy 254 133.985) (xy 254 154.305)
		)
		(stroke
			(width 0)
			(type default)
		)
	)
	(wire
		(pts
			(xy 205.74 83.82) (xy 205.74 86.36)
		)
		(stroke
			(width 0)
			(type default)
		)
	)
	(wire
		(pts
			(xy 299.085 200.025) (xy 299.085 202.565)
		)
		(stroke
			(width 0)
			(type default)
		)
	)
	(wire
		(pts
			(xy 213.36 210.82) (xy 213.36 213.36)
		)
		(stroke
			(width 0)
			(type default)
		)
	)
	(wire
		(pts
			(xy 171.45 109.22) (xy 171.45 111.76)
		)
		(stroke
			(width 0)
			(type default)
		)
	)
	(wire
		(pts
			(xy 205.74 111.76) (xy 205.74 113.03)
		)
		(stroke
			(width 0)
			(type default)
		)
	)
	(wire
		(pts
			(xy 249.555 197.485) (xy 249.555 200.025)
		)
		(stroke
			(width 0)
			(type default)
		)
	)
	(wire
		(pts
			(xy 200.025 83.82) (xy 205.74 83.82)
		)
		(stroke
			(width 0)
			(type default)
		)
	)
	(wire
		(pts
			(xy 205.74 81.28) (xy 205.74 83.82)
		)
		(stroke
			(width 0)
			(type default)
		)
	)
	(wire
		(pts
			(xy 205.74 71.12) (xy 200.025 71.12)
		)
		(stroke
			(width 0)
			(type default)
		)
	)
	(wire
		(pts
			(xy 205.74 68.58) (xy 200.025 68.58)
		)
		(stroke
			(width 0)
			(type default)
		)
	)
	(wire
		(pts
			(xy 205.74 86.36) (xy 200.025 86.36)
		)
		(stroke
			(width 0)
			(type default)
		)
	)
	(wire
		(pts
			(xy 177.165 71.12) (xy 171.45 71.12)
		)
		(stroke
			(width 0)
			(type default)
		)
	)
	(wire
		(pts
			(xy 249.555 151.765) (xy 262.89 151.765)
		)
		(stroke
			(width 0)
			(type default)
		)
	)
	(wire
		(pts
			(xy 200.025 73.66) (xy 205.74 73.66)
		)
		(stroke
			(width 0)
			(type default)
		)
	)
	(wire
		(pts
			(xy 200.025 218.44) (xy 202.565 218.44)
		)
		(stroke
			(width 0)
			(type default)
		)
	)
	(wire
		(pts
			(xy 285.75 139.065) (xy 287.655 139.065)
		)
		(stroke
			(width 0)
			(type default)
		)
	)
	(wire
		(pts
			(xy 177.165 170.18) (xy 163.83 170.18)
		)
		(stroke
			(width 0)
			(type default)
		)
	)
	(wire
		(pts
			(xy 177.165 177.8) (xy 163.83 177.8)
		)
		(stroke
			(width 0)
			(type default)
		)
	)
	(wire
		(pts
			(xy 171.45 81.28) (xy 171.45 83.82)
		)
		(stroke
			(width 0)
			(type default)
		)
	)
	(wire
		(pts
			(xy 250.19 128.905) (xy 262.89 128.905)
		)
		(stroke
			(width 0)
			(type default)
		)
	)
	(wire
		(pts
			(xy 295.91 113.665) (xy 285.75 113.665)
		)
		(stroke
			(width 0)
			(type default)
		)
	)
	(wire
		(pts
			(xy 177.165 86.36) (xy 171.45 86.36)
		)
		(stroke
			(width 0)
			(type default)
		)
	)
	(wire
		(pts
			(xy 205.74 53.34) (xy 205.74 55.88)
		)
		(stroke
			(width 0)
			(type default)
		)
	)
	(wire
		(pts
			(xy 200.025 205.74) (xy 213.36 205.74)
		)
		(stroke
			(width 0)
			(type default)
		)
	)
	(wire
		(pts
			(xy 250.19 136.525) (xy 262.89 136.525)
		)
		(stroke
			(width 0)
			(type default)
		)
	)
	(wire
		(pts
			(xy 205.74 104.14) (xy 205.74 106.68)
		)
		(stroke
			(width 0)
			(type default)
		)
	)
	(wire
		(pts
			(xy 200.025 58.42) (xy 205.74 58.42)
		)
		(stroke
			(width 0)
			(type default)
		)
	)
	(wire
		(pts
			(xy 213.36 200.66) (xy 213.36 203.2)
		)
		(stroke
			(width 0)
			(type default)
		)
	)
	(wire
		(pts
			(xy 255.905 65.405) (xy 262.89 65.405)
		)
		(stroke
			(width 0)
			(type default)
		)
	)
	(wire
		(pts
			(xy 301.625 197.485) (xy 299.085 197.485)
		)
		(stroke
			(width 0)
			(type default)
		)
	)
	(wire
		(pts
			(xy 205.74 71.12) (xy 205.74 73.66)
		)
		(stroke
			(width 0)
			(type default)
		)
	)
	(wire
		(pts
			(xy 255.905 62.865) (xy 262.89 62.865)
		)
		(stroke
			(width 0)
			(type default)
		)
	)
	(wire
		(pts
			(xy 213.36 213.36) (xy 200.025 213.36)
		)
		(stroke
			(width 0)
			(type default)
		)
	)
	(wire
		(pts
			(xy 171.45 58.42) (xy 177.165 58.42)
		)
		(stroke
			(width 0)
			(type default)
		)
	)
	(wire
		(pts
			(xy 249.555 210.185) (xy 249.555 212.725)
		)
		(stroke
			(width 0)
			(type default)
		)
	)
	(wire
		(pts
			(xy 161.29 167.64) (xy 163.83 167.64)
		)
		(stroke
			(width 0)
			(type default)
		)
	)
	(wire
		(pts
			(xy 205.74 93.98) (xy 205.74 96.52)
		)
		(stroke
			(width 0)
			(type default)
		)
	)
	(wire
		(pts
			(xy 177.165 83.82) (xy 171.45 83.82)
		)
		(stroke
			(width 0)
			(type default)
		)
	)
	(wire
		(pts
			(xy 262.89 95.885) (xy 250.825 95.885)
		)
		(stroke
			(width 0)
			(type default)
		)
	)
	(wire
		(pts
			(xy 295.91 108.585) (xy 285.75 108.585)
		)
		(stroke
			(width 0)
			(type default)
		)
	)
	(wire
		(pts
			(xy 250.19 121.285) (xy 262.89 121.285)
		)
		(stroke
			(width 0)
			(type default)
		)
	)
	(wire
		(pts
			(xy 250.19 123.825) (xy 262.89 123.825)
		)
		(stroke
			(width 0)
			(type default)
		)
	)
	(wire
		(pts
			(xy 177.165 91.44) (xy 171.45 91.44)
		)
		(stroke
			(width 0)
			(type default)
		)
	)
	(wire
		(pts
			(xy 177.165 76.2) (xy 171.45 76.2)
		)
		(stroke
			(width 0)
			(type default)
		)
	)
	(wire
		(pts
			(xy 171.45 73.66) (xy 171.45 76.2)
		)
		(stroke
			(width 0)
			(type default)
		)
	)
	(wire
		(pts
			(xy 249.555 215.265) (xy 262.89 215.265)
		)
		(stroke
			(width 0)
			(type default)
		)
	)
	(wire
		(pts
			(xy 262.89 197.485) (xy 249.555 197.485)
		)
		(stroke
			(width 0)
			(type default)
		)
	)
	(wire
		(pts
			(xy 254 154.305) (xy 254 217.805)
		)
		(stroke
			(width 0)
			(type default)
		)
	)
	(wire
		(pts
			(xy 200.025 200.66) (xy 213.36 200.66)
		)
		(stroke
			(width 0)
			(type default)
		)
	)
	(wire
		(pts
			(xy 295.91 121.285) (xy 285.75 121.285)
		)
		(stroke
			(width 0)
			(type default)
		)
	)
	(wire
		(pts
			(xy 285.75 197.485) (xy 299.085 197.485)
		)
		(stroke
			(width 0)
			(type default)
		)
	)
	(wire
		(pts
			(xy 262.89 100.965) (xy 250.825 100.965)
		)
		(stroke
			(width 0)
			(type default)
		)
	)
	(wire
		(pts
			(xy 213.36 203.2) (xy 213.36 205.74)
		)
		(stroke
			(width 0)
			(type default)
		)
	)
	(wire
		(pts
			(xy 200.025 88.9) (xy 205.74 88.9)
		)
		(stroke
			(width 0)
			(type default)
		)
	)
	(wire
		(pts
			(xy 285.75 207.645) (xy 299.085 207.645)
		)
		(stroke
			(width 0)
			(type default)
		)
	)
	(wire
		(pts
			(xy 205.74 106.68) (xy 200.025 106.68)
		)
		(stroke
			(width 0)
			(type default)
		)
	)
	(wire
		(pts
			(xy 205.74 76.2) (xy 205.74 78.74)
		)
		(stroke
			(width 0)
			(type default)
		)
	)
	(wire
		(pts
			(xy 295.91 106.045) (xy 285.75 106.045)
		)
		(stroke
			(width 0)
			(type default)
		)
	)
	(wire
		(pts
			(xy 285.75 136.525) (xy 295.91 136.525)
		)
		(stroke
			(width 0)
			(type default)
		)
	)
	(wire
		(pts
			(xy 177.165 111.76) (xy 171.45 111.76)
		)
		(stroke
			(width 0)
			(type default)
		)
	)
	(wire
		(pts
			(xy 177.165 63.5) (xy 171.45 63.5)
		)
		(stroke
			(width 0)
			(type default)
		)
	)
	(wire
		(pts
			(xy 171.45 71.12) (xy 171.45 73.66)
		)
		(stroke
			(width 0)
			(type default)
		)
	)
	(wire
		(pts
			(xy 249.555 146.685) (xy 262.89 146.685)
		)
		(stroke
			(width 0)
			(type default)
		)
	)
	(wire
		(pts
			(xy 262.89 111.125) (xy 254 111.125)
		)
		(stroke
			(width 0)
			(type default)
		)
	)
	(wire
		(pts
			(xy 213.36 208.28) (xy 213.36 210.82)
		)
		(stroke
			(width 0)
			(type default)
		)
	)
	(wire
		(pts
			(xy 285.75 133.985) (xy 295.91 133.985)
		)
		(stroke
			(width 0)
			(type default)
		)
	)
	(wire
		(pts
			(xy 250.19 139.065) (xy 262.89 139.065)
		)
		(stroke
			(width 0)
			(type default)
		)
	)
	(wire
		(pts
			(xy 205.74 109.22) (xy 205.74 111.76)
		)
		(stroke
			(width 0)
			(type default)
		)
	)
	(wire
		(pts
			(xy 177.165 66.04) (xy 171.45 66.04)
		)
		(stroke
			(width 0)
			(type default)
		)
	)
	(wire
		(pts
			(xy 177.165 167.64) (xy 163.83 167.64)
		)
		(stroke
			(width 0)
			(type default)
		)
	)
	(wire
		(pts
			(xy 177.165 53.34) (xy 171.45 53.34)
		)
		(stroke
			(width 0)
			(type default)
		)
	)
	(wire
		(pts
			(xy 250.19 103.505) (xy 262.89 103.505)
		)
		(stroke
			(width 0)
			(type default)
		)
	)
	(wire
		(pts
			(xy 171.45 96.52) (xy 171.45 99.06)
		)
		(stroke
			(width 0)
			(type default)
		)
	)
	(wire
		(pts
			(xy 295.91 85.725) (xy 285.75 85.725)
		)
		(stroke
			(width 0)
			(type default)
		)
	)
	(wire
		(pts
			(xy 285.75 100.965) (xy 295.91 100.965)
		)
		(stroke
			(width 0)
			(type default)
		)
	)
	(wire
		(pts
			(xy 295.91 88.265) (xy 285.75 88.265)
		)
		(stroke
			(width 0)
			(type default)
		)
	)
	(wire
		(pts
			(xy 299.085 200.025) (xy 285.75 200.025)
		)
		(stroke
			(width 0)
			(type default)
		)
	)
	(wire
		(pts
			(xy 285.75 149.225) (xy 295.91 149.225)
		)
		(stroke
			(width 0)
			(type default)
		)
	)
	(wire
		(pts
			(xy 171.45 66.04) (xy 171.45 68.58)
		)
		(stroke
			(width 0)
			(type default)
		)
	)
	(wire
		(pts
			(xy 177.165 104.14) (xy 171.45 104.14)
		)
		(stroke
			(width 0)
			(type default)
		)
	)
	(wire
		(pts
			(xy 295.91 95.885) (xy 285.75 95.885)
		)
		(stroke
			(width 0)
			(type default)
		)
	)
	(wire
		(pts
			(xy 163.83 172.72) (xy 163.83 175.26)
		)
		(stroke
			(width 0)
			(type default)
		)
	)
	(wire
		(pts
			(xy 287.655 118.745) (xy 287.655 139.065)
		)
		(stroke
			(width 0)
			(type default)
		)
	)
	(wire
		(pts
			(xy 177.165 73.66) (xy 171.45 73.66)
		)
		(stroke
			(width 0)
			(type default)
		)
	)
	(wire
		(pts
			(xy 177.165 101.6) (xy 171.45 101.6)
		)
		(stroke
			(width 0)
			(type default)
		)
	)
	(wire
		(pts
			(xy 177.165 172.72) (xy 163.83 172.72)
		)
		(stroke
			(width 0)
			(type default)
		)
	)
	(wire
		(pts
			(xy 163.83 167.64) (xy 163.83 170.18)
		)
		(stroke
			(width 0)
			(type default)
		)
	)
	(wire
		(pts
			(xy 299.085 207.645) (xy 299.085 210.185)
		)
		(stroke
			(width 0)
			(type default)
		)
	)
	(wire
		(pts
			(xy 205.74 55.88) (xy 200.025 55.88)
		)
		(stroke
			(width 0)
			(type default)
		)
	)
	(wire
		(pts
			(xy 177.165 109.22) (xy 171.45 109.22)
		)
		(stroke
			(width 0)
			(type default)
		)
	)
	(wire
		(pts
			(xy 285.75 111.125) (xy 295.91 111.125)
		)
		(stroke
			(width 0)
			(type default)
		)
	)
	(wire
		(pts
			(xy 163.83 180.34) (xy 163.83 182.88)
		)
		(stroke
			(width 0)
			(type default)
		)
	)
	(wire
		(pts
			(xy 249.555 205.105) (xy 262.89 205.105)
		)
		(stroke
			(width 0)
			(type default)
		)
	)
	(wire
		(pts
			(xy 249.555 205.105) (xy 249.555 207.645)
		)
		(stroke
			(width 0)
			(type default)
		)
	)
	(wire
		(pts
			(xy 171.45 91.44) (xy 171.45 93.98)
		)
		(stroke
			(width 0)
			(type default)
		)
	)
	(wire
		(pts
			(xy 250.19 131.445) (xy 262.89 131.445)
		)
		(stroke
			(width 0)
			(type default)
		)
	)
	(wire
		(pts
			(xy 177.165 78.74) (xy 171.45 78.74)
		)
		(stroke
			(width 0)
			(type default)
		)
	)
	(wire
		(pts
			(xy 171.45 83.82) (xy 171.45 86.36)
		)
		(stroke
			(width 0)
			(type default)
		)
	)
	(wire
		(pts
			(xy 250.19 108.585) (xy 262.89 108.585)
		)
		(stroke
			(width 0)
			(type default)
		)
	)
	(wire
		(pts
			(xy 171.45 53.34) (xy 171.45 55.88)
		)
		(stroke
			(width 0)
			(type default)
		)
	)
	(wire
		(pts
			(xy 250.19 141.605) (xy 262.89 141.605)
		)
		(stroke
			(width 0)
			(type default)
		)
	)
	(wire
		(pts
			(xy 285.75 98.425) (xy 287.655 98.425)
		)
		(stroke
			(width 0)
			(type default)
		)
	)
	(wire
		(pts
			(xy 262.89 154.305) (xy 254 154.305)
		)
		(stroke
			(width 0)
			(type default)
		)
	)
	(wire
		(pts
			(xy 255.905 67.945) (xy 262.89 67.945)
		)
		(stroke
			(width 0)
			(type default)
		)
	)
	(wire
		(pts
			(xy 171.45 88.9) (xy 171.45 91.44)
		)
		(stroke
			(width 0)
			(type default)
		)
	)
	(wire
		(pts
			(xy 262.89 207.645) (xy 249.555 207.645)
		)
		(stroke
			(width 0)
			(type default)
		)
	)
	(wire
		(pts
			(xy 285.75 131.445) (xy 295.91 131.445)
		)
		(stroke
			(width 0)
			(type default)
		)
	)
	(wire
		(pts
			(xy 205.74 91.44) (xy 200.025 91.44)
		)
		(stroke
			(width 0)
			(type default)
		)
	)
	(wire
		(pts
			(xy 200.025 104.14) (xy 205.74 104.14)
		)
		(stroke
			(width 0)
			(type default)
		)
	)
	(wire
		(pts
			(xy 205.74 78.74) (xy 205.74 81.28)
		)
		(stroke
			(width 0)
			(type default)
		)
	)
	(wire
		(pts
			(xy 205.74 66.04) (xy 205.74 68.58)
		)
		(stroke
			(width 0)
			(type default)
		)
	)
	(wire
		(pts
			(xy 177.165 180.34) (xy 163.83 180.34)
		)
		(stroke
			(width 0)
			(type default)
		)
	)
	(wire
		(pts
			(xy 254 111.125) (xy 254 133.985)
		)
		(stroke
			(width 0)
			(type default)
		)
	)
	(wire
		(pts
			(xy 171.45 76.2) (xy 171.45 78.74)
		)
		(stroke
			(width 0)
			(type default)
		)
	)
	(wire
		(pts
			(xy 171.45 106.68) (xy 171.45 109.22)
		)
		(stroke
			(width 0)
			(type default)
		)
	)
	(wire
		(pts
			(xy 205.74 73.66) (xy 205.74 76.2)
		)
		(stroke
			(width 0)
			(type default)
		)
	)
	(wire
		(pts
			(xy 171.45 50.8) (xy 171.45 53.34)
		)
		(stroke
			(width 0)
			(type default)
		)
	)
	(wire
		(pts
			(xy 171.45 86.36) (xy 171.45 88.9)
		)
		(stroke
			(width 0)
			(type default)
		)
	)
	(wire
		(pts
			(xy 285.75 212.725) (xy 299.085 212.725)
		)
		(stroke
			(width 0)
			(type default)
		)
	)
	(wire
		(pts
			(xy 285.75 128.905) (xy 296.545 128.905)
		)
		(stroke
			(width 0)
			(type default)
		)
	)
	(wire
		(pts
			(xy 205.74 50.8) (xy 205.74 53.34)
		)
		(stroke
			(width 0)
			(type default)
		)
	)
	(wire
		(pts
			(xy 262.89 202.565) (xy 249.555 202.565)
		)
		(stroke
			(width 0)
			(type default)
		)
	)
	(wire
		(pts
			(xy 205.74 63.5) (xy 205.74 66.04)
		)
		(stroke
			(width 0)
			(type default)
		)
	)
	(wire
		(pts
			(xy 200.025 109.22) (xy 205.74 109.22)
		)
		(stroke
			(width 0)
			(type default)
		)
	)
	(wire
		(pts
			(xy 213.36 195.58) (xy 215.265 195.58)
		)
		(stroke
			(width 0)
			(type default)
		)
	)
	(wire
		(pts
			(xy 250.19 116.205) (xy 262.89 116.205)
		)
		(stroke
			(width 0)
			(type default)
		)
	)
	(wire
		(pts
			(xy 299.085 202.565) (xy 285.75 202.565)
		)
		(stroke
			(width 0)
			(type default)
		)
	)
	(wire
		(pts
			(xy 262.89 98.425) (xy 250.825 98.425)
		)
		(stroke
			(width 0)
			(type default)
		)
	)
	(wire
		(pts
			(xy 177.165 93.98) (xy 171.45 93.98)
		)
		(stroke
			(width 0)
			(type default)
		)
	)
	(wire
		(pts
			(xy 262.89 90.805) (xy 254 90.805)
		)
		(stroke
			(width 0)
			(type default)
		)
	)
	(wire
		(pts
			(xy 295.91 83.185) (xy 285.75 83.185)
		)
		(stroke
			(width 0)
			(type default)
		)
	)
	(wire
		(pts
			(xy 200.025 203.2) (xy 213.36 203.2)
		)
		(stroke
			(width 0)
			(type default)
		)
	)
	(wire
		(pts
			(xy 200.025 195.58) (xy 213.36 195.58)
		)
		(stroke
			(width 0)
			(type default)
		)
	)
	(wire
		(pts
			(xy 299.085 210.185) (xy 299.085 212.725)
		)
		(stroke
			(width 0)
			(type default)
		)
	)
	(wire
		(pts
			(xy 205.74 58.42) (xy 205.74 60.96)
		)
		(stroke
			(width 0)
			(type default)
		)
	)
	(wire
		(pts
			(xy 249.555 207.645) (xy 249.555 210.185)
		)
		(stroke
			(width 0)
			(type default)
		)
	)
	(wire
		(pts
			(xy 171.45 58.42) (xy 171.45 60.96)
		)
		(stroke
			(width 0)
			(type default)
		)
	)
	(wire
		(pts
			(xy 255.905 52.705) (xy 262.89 52.705)
		)
		(stroke
			(width 0)
			(type default)
		)
	)
	(wire
		(pts
			(xy 170.18 210.82) (xy 177.165 210.82)
		)
		(stroke
			(width 0)
			(type default)
		)
	)
	(global_label "CA2_A"
		(shape input)
		(at 295.91 90.805 0)
		(fields_autoplaced yes)
		(effects
			(font
				(size 1.27 1.27)
			)
			(justify left)
		)
		(property "Intersheetrefs" "${INTERSHEET_REFS}"
			(at -2.54 0 0)
			(effects
				(font
					(size 1.27 1.27)
				)
				(hide yes)
			)
		)
	)
	(global_label "1V1_DDR"
		(shape input)
		(at 247.015 197.485 180)
		(fields_autoplaced yes)
		(effects
			(font
				(size 1.27 1.27)
			)
			(justify right)
		)
		(property "Intersheetrefs" "${INTERSHEET_REFS}"
			(at 236.4056 197.4056 0)
			(effects
				(font
					(size 1.27 1.27)
				)
				(justify right)
				(hide yes)
			)
		)
	)
	(global_label "DQ13_A"
		(shape input)
		(at 250.19 118.745 180)
		(fields_autoplaced yes)
		(effects
			(font
				(size 1.27 1.27)
			)
			(justify right)
		)
		(property "Intersheetrefs" "${INTERSHEET_REFS}"
			(at 240.7833 118.745 0)
			(effects
				(font
					(size 1.27 1.27)
				)
				(justify right)
				(hide yes)
			)
		)
	)
	(global_label "DQ_S0_P"
		(shape input)
		(at 250.19 141.605 180)
		(fields_autoplaced yes)
		(effects
			(font
				(size 1.27 1.27)
			)
			(justify right)
		)
		(property "Intersheetrefs" "${INTERSHEET_REFS}"
			(at 239.641 141.5256 0)
			(effects
				(font
					(size 1.27 1.27)
				)
				(justify right)
				(hide yes)
			)
		)
	)
	(global_label "1V8_DDR"
		(shape input)
		(at 301.625 205.105 0)
		(fields_autoplaced yes)
		(effects
			(font
				(size 1.27 1.27)
			)
			(justify left)
		)
		(property "Intersheetrefs" "${INTERSHEET_REFS}"
			(at 312.2344 205.0256 0)
			(effects
				(font
					(size 1.27 1.27)
				)
				(justify left)
				(hide yes)
			)
		)
	)
	(global_label "DQ_S1_P"
		(shape input)
		(at 250.19 108.585 180)
		(fields_autoplaced yes)
		(effects
			(font
				(size 1.27 1.27)
			)
			(justify right)
		)
		(property "Intersheetrefs" "${INTERSHEET_REFS}"
			(at 239.641 108.5056 0)
			(effects
				(font
					(size 1.27 1.27)
				)
				(justify right)
				(hide yes)
			)
		)
	)
	(global_label "DQ12_A"
		(shape input)
		(at 250.19 121.285 180)
		(fields_autoplaced yes)
		(effects
			(font
				(size 1.27 1.27)
			)
			(justify right)
		)
		(property "Intersheetrefs" "${INTERSHEET_REFS}"
			(at 240.7833 121.285 0)
			(effects
				(font
					(size 1.27 1.27)
				)
				(justify right)
				(hide yes)
			)
		)
	)
	(global_label "IO_R4"
		(shape input)
		(at 295.91 116.205 0)
		(fields_autoplaced yes)
		(effects
			(font
				(size 1.27 1.27)
			)
			(justify left)
		)
		(property "Intersheetrefs" "${INTERSHEET_REFS}"
			(at -2.54 0 0)
			(effects
				(font
					(size 1.27 1.27)
				)
				(hide yes)
			)
		)
	)
	(global_label "DQ00_A"
		(shape input)
		(at 249.555 144.145 180)
		(fields_autoplaced yes)
		(effects
			(font
				(size 1.27 1.27)
			)
			(justify right)
		)
		(property "Intersheetrefs" "${INTERSHEET_REFS}"
			(at 240.1483 144.145 0)
			(effects
				(font
					(size 1.27 1.27)
				)
				(justify right)
				(hide yes)
			)
		)
	)
	(global_label "IO_Y12"
		(shape input)
		(at 255.905 55.245 180)
		(fields_autoplaced yes)
		(effects
			(font
				(size 1.27 1.27)
			)
			(justify right)
		)
		(property "Intersheetrefs" "${INTERSHEET_REFS}"
			(at 247.1635 55.245 0)
			(effects
				(font
					(size 1.27 1.27)
				)
				(justify right)
				(hide yes)
			)
		)
	)
	(global_label "DQ01_A"
		(shape input)
		(at 249.555 146.685 180)
		(fields_autoplaced yes)
		(effects
			(font
				(size 1.27 1.27)
			)
			(justify right)
		)
		(property "Intersheetrefs" "${INTERSHEET_REFS}"
			(at 240.1483 146.685 0)
			(effects
				(font
					(size 1.27 1.27)
				)
				(justify right)
				(hide yes)
			)
		)
	)
	(global_label "CA_1A"
		(shape input)
		(at 295.91 146.685 0)
		(fields_autoplaced yes)
		(effects
			(font
				(size 1.27 1.27)
			)
			(justify left)
		)
		(property "Intersheetrefs" "${INTERSHEET_REFS}"
			(at -2.54 0 0)
			(effects
				(font
					(size 1.27 1.27)
				)
				(hide yes)
			)
		)
	)
	(global_label "VDDQ"
		(shape input)
		(at 301.625 197.485 0)
		(fields_autoplaced yes)
		(effects
			(font
				(size 1.27 1.27)
			)
			(justify left)
		)
		(property "Intersheetrefs" "${INTERSHEET_REFS}"
			(at -2.54 0 0)
			(effects
				(font
					(size 1.27 1.27)
				)
				(hide yes)
			)
		)
	)
	(global_label "IO_AB10"
		(shape input)
		(at 255.905 67.945 180)
		(fields_autoplaced yes)
		(effects
			(font
				(size 1.27 1.27)
			)
			(justify right)
		)
		(property "Intersheetrefs" "${INTERSHEET_REFS}"
			(at 245.8935 67.945 0)
			(effects
				(font
					(size 1.27 1.27)
				)
				(justify right)
				(hide yes)
			)
		)
	)
	(global_label "CA3_A"
		(shape input)
		(at 295.91 88.265 0)
		(fields_autoplaced yes)
		(effects
			(font
				(size 1.27 1.27)
			)
			(justify left)
		)
		(property "Intersheetrefs" "${INTERSHEET_REFS}"
			(at -2.54 0 0)
			(effects
				(font
					(size 1.27 1.27)
				)
				(hide yes)
			)
		)
	)
	(global_label "IO_N5"
		(shape input)
		(at 296.545 128.905 0)
		(fields_autoplaced yes)
		(effects
			(font
				(size 1.27 1.27)
			)
			(justify left)
		)
		(property "Intersheetrefs" "${INTERSHEET_REFS}"
			(at -2.54 0 0)
			(effects
				(font
					(size 1.27 1.27)
				)
				(hide yes)
			)
		)
	)
	(global_label "IO_W4"
		(shape input)
		(at 295.91 100.965 0)
		(fields_autoplaced yes)
		(effects
			(font
				(size 1.27 1.27)
			)
			(justify left)
		)
		(property "Intersheetrefs" "${INTERSHEET_REFS}"
			(at -2.54 0 0)
			(effects
				(font
					(size 1.27 1.27)
				)
				(hide yes)
			)
		)
	)
	(global_label "DQ02_A"
		(shape input)
		(at 249.555 149.225 180)
		(fields_autoplaced yes)
		(effects
			(font
				(size 1.27 1.27)
			)
			(justify right)
		)
		(property "Intersheetrefs" "${INTERSHEET_REFS}"
			(at 240.1483 149.225 0)
			(effects
				(font
					(size 1.27 1.27)
				)
				(justify right)
				(hide yes)
			)
		)
	)
	(global_label "DQ05_A"
		(shape input)
		(at 250.19 126.365 180)
		(fields_autoplaced yes)
		(effects
			(font
				(size 1.27 1.27)
			)
			(justify right)
		)
		(property "Intersheetrefs" "${INTERSHEET_REFS}"
			(at 240.7833 126.365 0)
			(effects
				(font
					(size 1.27 1.27)
				)
				(justify right)
				(hide yes)
			)
		)
	)
	(global_label "1V8_DDR"
		(shape input)
		(at 215.265 195.58 0)
		(fields_autoplaced yes)
		(effects
			(font
				(size 1.27 1.27)
			)
			(justify left)
		)
		(property "Intersheetrefs" "${INTERSHEET_REFS}"
			(at 225.8744 195.5006 0)
			(effects
				(font
					(size 1.27 1.27)
				)
				(justify left)
				(hide yes)
			)
		)
	)
	(global_label "IO_T4"
		(shape input)
		(at 295.91 113.665 0)
		(fields_autoplaced yes)
		(effects
			(font
				(size 1.27 1.27)
			)
			(justify left)
		)
		(property "Intersheetrefs" "${INTERSHEET_REFS}"
			(at -2.54 0 0)
			(effects
				(font
					(size 1.27 1.27)
				)
				(hide yes)
			)
		)
	)
	(global_label "DQ11_A"
		(shape input)
		(at 250.825 93.345 180)
		(fields_autoplaced yes)
		(effects
			(font
				(size 1.27 1.27)
			)
			(justify right)
		)
		(property "Intersheetrefs" "${INTERSHEET_REFS}"
			(at 241.4183 93.345 0)
			(effects
				(font
					(size 1.27 1.27)
				)
				(justify right)
				(hide yes)
			)
		)
	)
	(global_label "IO_M5"
		(shape input)
		(at 295.91 136.525 0)
		(fields_autoplaced yes)
		(effects
			(font
				(size 1.27 1.27)
			)
			(justify left)
		)
		(property "Intersheetrefs" "${INTERSHEET_REFS}"
			(at -2.54 0 0)
			(effects
				(font
					(size 1.27 1.27)
				)
				(hide yes)
			)
		)
	)
	(global_label "DQ_S0_N"
		(shape input)
		(at 250.19 139.065 180)
		(fields_autoplaced yes)
		(effects
			(font
				(size 1.27 1.27)
			)
			(justify right)
		)
		(property "Intersheetrefs" "${INTERSHEET_REFS}"
			(at 239.5806 138.9856 0)
			(effects
				(font
					(size 1.27 1.27)
				)
				(justify right)
				(hide yes)
			)
		)
	)
	(global_label "1V1_DDR"
		(shape input)
		(at 161.29 167.64 180)
		(fields_autoplaced yes)
		(effects
			(font
				(size 1.27 1.27)
			)
			(justify right)
		)
		(property "Intersheetrefs" "${INTERSHEET_REFS}"
			(at 150.6806 167.5606 0)
			(effects
				(font
					(size 1.27 1.27)
				)
				(justify right)
				(hide yes)
			)
		)
	)
	(global_label "DQ09_A"
		(shape input)
		(at 250.825 98.425 180)
		(fields_autoplaced yes)
		(effects
			(font
				(size 1.27 1.27)
			)
			(justify right)
		)
		(property "Intersheetrefs" "${INTERSHEET_REFS}"
			(at 241.4183 98.425 0)
			(effects
				(font
					(size 1.27 1.27)
				)
				(justify right)
				(hide yes)
			)
		)
	)
	(global_label "IO_W12"
		(shape input)
		(at 255.905 52.705 180)
		(fields_autoplaced yes)
		(effects
			(font
				(size 1.27 1.27)
			)
			(justify right)
		)
		(property "Intersheetrefs" "${INTERSHEET_REFS}"
			(at 246.8007 52.705 0)
			(effects
				(font
					(size 1.27 1.27)
				)
				(justify right)
				(hide yes)
			)
		)
	)
	(global_label "DQ06_A"
		(shape input)
		(at 250.19 128.905 180)
		(fields_autoplaced yes)
		(effects
			(font
				(size 1.27 1.27)
			)
			(justify right)
		)
		(property "Intersheetrefs" "${INTERSHEET_REFS}"
			(at 240.7833 128.905 0)
			(effects
				(font
					(size 1.27 1.27)
				)
				(justify right)
				(hide yes)
			)
		)
	)
	(global_label "DQ14_A"
		(shape input)
		(at 250.19 116.205 180)
		(fields_autoplaced yes)
		(effects
			(font
				(size 1.27 1.27)
			)
			(justify right)
		)
		(property "Intersheetrefs" "${INTERSHEET_REFS}"
			(at 240.7833 116.205 0)
			(effects
				(font
					(size 1.27 1.27)
				)
				(justify right)
				(hide yes)
			)
		)
	)
	(global_label "DQ10_A"
		(shape input)
		(at 250.825 95.885 180)
		(fields_autoplaced yes)
		(effects
			(font
				(size 1.27 1.27)
			)
			(justify right)
		)
		(property "Intersheetrefs" "${INTERSHEET_REFS}"
			(at 241.4183 95.885 0)
			(effects
				(font
					(size 1.27 1.27)
				)
				(justify right)
				(hide yes)
			)
		)
	)
	(global_label "IO_Y11"
		(shape input)
		(at 255.905 60.325 180)
		(fields_autoplaced yes)
		(effects
			(font
				(size 1.27 1.27)
			)
			(justify right)
		)
		(property "Intersheetrefs" "${INTERSHEET_REFS}"
			(at 247.1635 60.325 0)
			(effects
				(font
					(size 1.27 1.27)
				)
				(justify right)
				(hide yes)
			)
		)
	)
	(global_label "CK_A_N"
		(shape input)
		(at 295.91 93.345 0)
		(fields_autoplaced yes)
		(effects
			(font
				(size 1.27 1.27)
			)
			(justify left)
		)
		(property "Intersheetrefs" "${INTERSHEET_REFS}"
			(at 305.1285 93.2656 0)
			(effects
				(font
					(size 1.27 1.27)
				)
				(justify left)
				(hide yes)
			)
		)
	)
	(global_label "DQ07_A"
		(shape input)
		(at 250.19 131.445 180)
		(fields_autoplaced yes)
		(effects
			(font
				(size 1.27 1.27)
			)
			(justify right)
		)
		(property "Intersheetrefs" "${INTERSHEET_REFS}"
			(at 240.7833 131.445 0)
			(effects
				(font
					(size 1.27 1.27)
				)
				(justify right)
				(hide yes)
			)
		)
	)
	(global_label "CA5_A"
		(shape input)
		(at 295.91 83.185 0)
		(fields_autoplaced yes)
		(effects
			(font
				(size 1.27 1.27)
			)
			(justify left)
		)
		(property "Intersheetrefs" "${INTERSHEET_REFS}"
			(at -2.54 0 0)
			(effects
				(font
					(size 1.27 1.27)
				)
				(hide yes)
			)
		)
	)
	(global_label "DQ15_A"
		(shape input)
		(at 250.19 113.665 180)
		(fields_autoplaced yes)
		(effects
			(font
				(size 1.27 1.27)
			)
			(justify right)
		)
		(property "Intersheetrefs" "${INTERSHEET_REFS}"
			(at 240.7833 113.665 0)
			(effects
				(font
					(size 1.27 1.27)
				)
				(justify right)
				(hide yes)
			)
		)
	)
	(global_label "CA4_A"
		(shape input)
		(at 295.91 85.725 0)
		(fields_autoplaced yes)
		(effects
			(font
				(size 1.27 1.27)
			)
			(justify left)
		)
		(property "Intersheetrefs" "${INTERSHEET_REFS}"
			(at -2.54 0 0)
			(effects
				(font
					(size 1.27 1.27)
				)
				(hide yes)
			)
		)
	)
	(global_label "IO_V3"
		(shape input)
		(at 295.91 103.505 0)
		(fields_autoplaced yes)
		(effects
			(font
				(size 1.27 1.27)
			)
			(justify left)
		)
		(property "Intersheetrefs" "${INTERSHEET_REFS}"
			(at -2.54 0 0)
			(effects
				(font
					(size 1.27 1.27)
				)
				(hide yes)
			)
		)
	)
	(global_label "CKE0_A"
		(shape input)
		(at 295.91 133.985 0)
		(fields_autoplaced yes)
		(effects
			(font
				(size 1.27 1.27)
			)
			(justify left)
		)
		(property "Intersheetrefs" "${INTERSHEET_REFS}"
			(at -2.54 0 0)
			(effects
				(font
					(size 1.27 1.27)
				)
				(hide yes)
			)
		)
	)
	(global_label "IO_K4"
		(shape input)
		(at 295.91 149.225 0)
		(fields_autoplaced yes)
		(effects
			(font
				(size 1.27 1.27)
			)
			(justify left)
		)
		(property "Intersheetrefs" "${INTERSHEET_REFS}"
			(at -2.54 0 0)
			(effects
				(font
					(size 1.27 1.27)
				)
				(hide yes)
			)
		)
	)
	(global_label "IO_AB11"
		(shape input)
		(at 255.905 65.405 180)
		(fields_autoplaced yes)
		(effects
			(font
				(size 1.27 1.27)
			)
			(justify right)
		)
		(property "Intersheetrefs" "${INTERSHEET_REFS}"
			(at 245.8935 65.405 0)
			(effects
				(font
					(size 1.27 1.27)
				)
				(justify right)
				(hide yes)
			)
		)
	)
	(global_label "CS0_A"
		(shape input)
		(at 295.91 131.445 0)
		(fields_autoplaced yes)
		(effects
			(font
				(size 1.27 1.27)
			)
			(justify left)
		)
		(property "Intersheetrefs" "${INTERSHEET_REFS}"
			(at -2.54 0 0)
			(effects
				(font
					(size 1.27 1.27)
				)
				(hide yes)
			)
		)
	)
	(global_label "IO_W11"
		(shape input)
		(at 255.905 57.785 180)
		(fields_autoplaced yes)
		(effects
			(font
				(size 1.27 1.27)
			)
			(justify right)
		)
		(property "Intersheetrefs" "${INTERSHEET_REFS}"
			(at 246.8007 57.785 0)
			(effects
				(font
					(size 1.27 1.27)
				)
				(justify right)
				(hide yes)
			)
		)
	)
	(global_label "IO_AA11"
		(shape input)
		(at 255.905 62.865 180)
		(fields_autoplaced yes)
		(effects
			(font
				(size 1.27 1.27)
			)
			(justify right)
		)
		(property "Intersheetrefs" "${INTERSHEET_REFS}"
			(at 246.0749 62.865 0)
			(effects
				(font
					(size 1.27 1.27)
				)
				(justify right)
				(hide yes)
			)
		)
	)
	(global_label "IO_P4"
		(shape input)
		(at 295.91 121.285 0)
		(fields_autoplaced yes)
		(effects
			(font
				(size 1.27 1.27)
			)
			(justify left)
		)
		(property "Intersheetrefs" "${INTERSHEET_REFS}"
			(at -2.54 0 0)
			(effects
				(font
					(size 1.27 1.27)
				)
				(hide yes)
			)
		)
	)
	(global_label "CA_0A"
		(shape input)
		(at 295.91 144.145 0)
		(fields_autoplaced yes)
		(effects
			(font
				(size 1.27 1.27)
			)
			(justify left)
		)
		(property "Intersheetrefs" "${INTERSHEET_REFS}"
			(at -2.54 0 0)
			(effects
				(font
					(size 1.27 1.27)
				)
				(hide yes)
			)
		)
	)
	(global_label "DQ04_A"
		(shape input)
		(at 250.19 123.825 180)
		(fields_autoplaced yes)
		(effects
			(font
				(size 1.27 1.27)
			)
			(justify right)
		)
		(property "Intersheetrefs" "${INTERSHEET_REFS}"
			(at 240.7833 123.825 0)
			(effects
				(font
					(size 1.27 1.27)
				)
				(justify right)
				(hide yes)
			)
		)
	)
	(global_label "IO_U5"
		(shape input)
		(at 295.91 111.125 0)
		(fields_autoplaced yes)
		(effects
			(font
				(size 1.27 1.27)
			)
			(justify left)
		)
		(property "Intersheetrefs" "${INTERSHEET_REFS}"
			(at -2.54 0 0)
			(effects
				(font
					(size 1.27 1.27)
				)
				(hide yes)
			)
		)
	)
	(global_label "DQ08_A"
		(shape input)
		(at 250.825 100.965 180)
		(fields_autoplaced yes)
		(effects
			(font
				(size 1.27 1.27)
			)
			(justify right)
		)
		(property "Intersheetrefs" "${INTERSHEET_REFS}"
			(at 241.4183 100.965 0)
			(effects
				(font
					(size 1.27 1.27)
				)
				(justify right)
				(hide yes)
			)
		)
	)
	(global_label "IO_V12"
		(shape input)
		(at 170.18 213.36 180)
		(fields_autoplaced yes)
		(effects
			(font
				(size 1.27 1.27)
			)
			(justify right)
		)
		(property "Intersheetrefs" "${INTERSHEET_REFS}"
			(at 161.4385 213.36 0)
			(effects
				(font
					(size 1.27 1.27)
				)
				(justify right)
				(hide yes)
			)
		)
	)
	(global_label "IO_U3"
		(shape input)
		(at 295.91 108.585 0)
		(fields_autoplaced yes)
		(effects
			(font
				(size 1.27 1.27)
			)
			(justify left)
		)
		(property "Intersheetrefs" "${INTERSHEET_REFS}"
			(at -2.54 0 0)
			(effects
				(font
					(size 1.27 1.27)
				)
				(hide yes)
			)
		)
	)
	(global_label "DMI_1A"
		(shape input)
		(at 250.19 103.505 180)
		(fields_autoplaced yes)
		(effects
			(font
				(size 1.27 1.27)
			)
			(justify right)
		)
		(property "Intersheetrefs" "${INTERSHEET_REFS}"
			(at 241.2671 103.505 0)
			(effects
				(font
					(size 1.27 1.27)
				)
				(justify right)
				(hide yes)
			)
		)
	)
	(global_label "VDDQ"
		(shape input)
		(at 215.9 208.28 0)
		(fields_autoplaced yes)
		(effects
			(font
				(size 1.27 1.27)
			)
			(justify left)
		)
		(property "Intersheetrefs" "${INTERSHEET_REFS}"
			(at -2.54 0 0)
			(effects
				(font
					(size 1.27 1.27)
				)
				(hide yes)
			)
		)
	)
	(global_label "IO_U12"
		(shape input)
		(at 170.18 210.82 180)
		(fields_autoplaced yes)
		(effects
			(font
				(size 1.27 1.27)
			)
			(justify right)
		)
		(property "Intersheetrefs" "${INTERSHEET_REFS}"
			(at 161.1966 210.82 0)
			(effects
				(font
					(size 1.27 1.27)
				)
				(justify right)
				(hide yes)
			)
		)
	)
	(global_label "DQ_S1_N"
		(shape input)
		(at 250.19 106.045 180)
		(fields_autoplaced yes)
		(effects
			(font
				(size 1.27 1.27)
			)
			(justify right)
		)
		(property "Intersheetrefs" "${INTERSHEET_REFS}"
			(at 239.5806 105.9656 0)
			(effects
				(font
					(size 1.27 1.27)
				)
				(justify right)
				(hide yes)
			)
		)
	)
	(global_label "IO_V4"
		(shape input)
		(at 295.91 106.045 0)
		(fields_autoplaced yes)
		(effects
			(font
				(size 1.27 1.27)
			)
			(justify left)
		)
		(property "Intersheetrefs" "${INTERSHEET_REFS}"
			(at -2.54 0 0)
			(effects
				(font
					(size 1.27 1.27)
				)
				(hide yes)
			)
		)
	)
	(global_label "CK_A_P"
		(shape input)
		(at 295.91 95.885 0)
		(fields_autoplaced yes)
		(effects
			(font
				(size 1.27 1.27)
			)
			(justify left)
		)
		(property "Intersheetrefs" "${INTERSHEET_REFS}"
			(at 305.068 95.8056 0)
			(effects
				(font
					(size 1.27 1.27)
				)
				(justify left)
				(hide yes)
			)
		)
	)
	(global_label "DQ03_A"
		(shape input)
		(at 249.555 151.765 180)
		(fields_autoplaced yes)
		(effects
			(font
				(size 1.27 1.27)
			)
			(justify right)
		)
		(property "Intersheetrefs" "${INTERSHEET_REFS}"
			(at 240.1483 151.765 0)
			(effects
				(font
					(size 1.27 1.27)
				)
				(justify right)
				(hide yes)
			)
		)
	)
	(global_label "DMI_0A"
		(shape input)
		(at 250.19 136.525 180)
		(fields_autoplaced yes)
		(effects
			(font
				(size 1.27 1.27)
			)
			(justify right)
		)
		(property "Intersheetrefs" "${INTERSHEET_REFS}"
			(at 241.2671 136.525 0)
			(effects
				(font
					(size 1.27 1.27)
				)
				(justify right)
				(hide yes)
			)
		)
	)
	(symbol
		(lib_id "antmicropower:GND")
		(at 171.45 112.395 0)
		(unit 1)
		(exclude_from_sim no)
		(in_bom yes)
		(on_board yes)
		(dnp no)
		(property "Reference" "#PWR0223"
			(at 171.45 118.745 0)
			(effects
				(font
					(size 1.27 1.27)
				)
				(justify left bottom)
				(hide yes)
			)
		)
		(property "Value" "GND"
			(at 171.577 116.7892 0)
			(effects
				(font
					(size 1.27 1.27)
				)
				(justify left bottom)
			)
		)
		(property "Footprint" ""
			(at 171.45 112.395 0)
			(effects
				(font
					(size 1.27 1.27)
				)
				(justify left bottom)
				(hide yes)
			)
		)
		(property "Datasheet" ""
			(at 171.45 112.395 0)
			(effects
				(font
					(size 1.27 1.27)
				)
				(justify left bottom)
				(hide yes)
			)
		)
		(property "Description" ""
			(at 171.45 112.395 0)
			(effects
				(font
					(size 1.27 1.27)
				)
			)
		)
		(pin "1"
		)
		(instances
			(project "lpddr4-test-board"
				(path ""
					(reference "#PWR0223")
					(unit 1)
				)
			)
		)
	)
	(symbol
		(lib_id "antmicroMemoryConnectorsPCCardSockets:Bus_DDR4_SODIMM_TE_2309409")
		(at 177.165 50.8 0)
		(unit 1)
		(exclude_from_sim no)
		(in_bom yes)
		(on_board yes)
		(dnp no)
		(property "Reference" "J9"
			(at 180.975 46.355 0)
			(effects
				(font
					(size 1.27 1.27)
				)
				(justify left bottom)
			)
		)
		(property "Value" "Bus_DDR4_SODIMM_TE_2309409"
			(at 213.995 58.42 0)
			(effects
				(font
					(size 1.27 1.27)
					(thickness 0.15)
				)
				(justify left bottom)
				(hide yes)
			)
		)
		(property "Footprint" "antmicro-footprints:Bus_DDR4_SODIMM_TE_2309409"
			(at 213.995 60.96 0)
			(effects
				(font
					(size 1.27 1.27)
					(thickness 0.15)
				)
				(justify left bottom)
				(hide yes)
			)
		)
		(property "Datasheet" "https://www.mouser.com/datasheet/2/418/7/ENG_CD_2309409_5-2032664.pdf"
			(at 213.995 63.5 0)
			(effects
				(font
					(size 1.27 1.27)
					(thickness 0.15)
				)
				(justify left bottom)
				(hide yes)
			)
		)
		(property "Description" ""
			(at 177.165 50.8 0)
			(effects
				(font
					(size 1.27 1.27)
				)
			)
		)
		(property "Manufacturer" "TE Connectivity"
			(at 213.995 66.04 0)
			(effects
				(font
					(size 1.27 1.27)
					(thickness 0.15)
				)
				(justify left bottom)
				(hide yes)
			)
		)
		(property "MPN" "2309409-1"
			(at 181.61 223.52 0)
			(effects
				(font
					(size 1.27 1.27)
					(thickness 0.15)
				)
				(justify left bottom)
			)
		)
		(property "Author" "Antmicro"
			(at 213.995 68.58 0)
			(effects
				(font
					(size 1.27 1.27)
					(thickness 0.15)
				)
				(justify left bottom)
				(hide yes)
			)
		)
		(property "License" "Apache-2.0"
			(at 213.995 71.12 0)
			(effects
				(font
					(size 1.27 1.27)
					(thickness 0.15)
				)
				(justify left bottom)
				(hide yes)
			)
		)
		(pin "1"
		)
		(pin "10"
		)
		(pin "100"
		)
		(pin "101"
		)
		(pin "102"
		)
		(pin "103"
		)
		(pin "104"
		)
		(pin "105"
		)
		(pin "106"
		)
		(pin "107"
		)
		(pin "108"
		)
		(pin "109"
		)
		(pin "11"
		)
		(pin "110"
		)
		(pin "111"
		)
		(pin "112"
		)
		(pin "113"
		)
		(pin "114"
		)
		(pin "115"
		)
		(pin "116"
		)
		(pin "117"
		)
		(pin "118"
		)
		(pin "119"
		)
		(pin "12"
		)
		(pin "120"
		)
		(pin "121"
		)
		(pin "122"
		)
		(pin "123"
		)
		(pin "124"
		)
		(pin "125"
		)
		(pin "126"
		)
		(pin "127"
		)
		(pin "128"
		)
		(pin "129"
		)
		(pin "13"
		)
		(pin "130"
		)
		(pin "14"
		)
		(pin "15"
		)
		(pin "16"
		)
		(pin "17"
		)
		(pin "18"
		)
		(pin "19"
		)
		(pin "2"
		)
		(pin "20"
		)
		(pin "21"
		)
		(pin "22"
		)
		(pin "23"
		)
		(pin "24"
		)
		(pin "25"
		)
		(pin "26"
		)
		(pin "27"
		)
		(pin "28"
		)
		(pin "29"
		)
		(pin "3"
		)
		(pin "30"
		)
		(pin "31"
		)
		(pin "32"
		)
		(pin "33"
		)
		(pin "34"
		)
		(pin "35"
		)
		(pin "36"
		)
		(pin "37"
		)
		(pin "38"
		)
		(pin "39"
		)
		(pin "4"
		)
		(pin "40"
		)
		(pin "41"
		)
		(pin "42"
		)
		(pin "43"
		)
		(pin "44"
		)
		(pin "45"
		)
		(pin "46"
		)
		(pin "47"
		)
		(pin "48"
		)
		(pin "49"
		)
		(pin "5"
		)
		(pin "50"
		)
		(pin "51"
		)
		(pin "52"
		)
		(pin "53"
		)
		(pin "54"
		)
		(pin "55"
		)
		(pin "56"
		)
		(pin "57"
		)
		(pin "58"
		)
		(pin "59"
		)
		(pin "6"
		)
		(pin "60"
		)
		(pin "61"
		)
		(pin "62"
		)
		(pin "63"
		)
		(pin "64"
		)
		(pin "65"
		)
		(pin "66"
		)
		(pin "67"
		)
		(pin "68"
		)
		(pin "69"
		)
		(pin "7"
		)
		(pin "70"
		)
		(pin "71"
		)
		(pin "72"
		)
		(pin "73"
		)
		(pin "74"
		)
		(pin "75"
		)
		(pin "76"
		)
		(pin "77"
		)
		(pin "78"
		)
		(pin "79"
		)
		(pin "8"
		)
		(pin "80"
		)
		(pin "81"
		)
		(pin "82"
		)
		(pin "83"
		)
		(pin "84"
		)
		(pin "85"
		)
		(pin "86"
		)
		(pin "87"
		)
		(pin "88"
		)
		(pin "89"
		)
		(pin "9"
		)
		(pin "90"
		)
		(pin "91"
		)
		(pin "92"
		)
		(pin "93"
		)
		(pin "94"
		)
		(pin "95"
		)
		(pin "96"
		)
		(pin "97"
		)
		(pin "98"
		)
		(pin "99"
		)
		(pin "S1"
		)
		(pin "S2"
		)
		(pin "256"
		)
		(pin "257"
		)
		(pin "258"
		)
		(pin "259"
		)
		(pin "260"
		)
		(pin "131"
		)
		(pin "132"
		)
		(pin "133"
		)
		(pin "134"
		)
		(pin "135"
		)
		(pin "136"
		)
		(pin "137"
		)
		(pin "138"
		)
		(pin "139"
		)
		(pin "140"
		)
		(pin "141"
		)
		(pin "142"
		)
		(pin "143"
		)
		(pin "144"
		)
		(pin "145"
		)
		(pin "146"
		)
		(pin "147"
		)
		(pin "148"
		)
		(pin "149"
		)
		(pin "150"
		)
		(pin "151"
		)
		(pin "152"
		)
		(pin "153"
		)
		(pin "154"
		)
		(pin "155"
		)
		(pin "156"
		)
		(pin "157"
		)
		(pin "158"
		)
		(pin "159"
		)
		(pin "160"
		)
		(pin "161"
		)
		(pin "162"
		)
		(pin "163"
		)
		(pin "164"
		)
		(pin "165"
		)
		(pin "166"
		)
		(pin "167"
		)
		(pin "168"
		)
		(pin "169"
		)
		(pin "170"
		)
		(pin "171"
		)
		(pin "172"
		)
		(pin "173"
		)
		(pin "174"
		)
		(pin "175"
		)
		(pin "176"
		)
		(pin "177"
		)
		(pin "178"
		)
		(pin "179"
		)
		(pin "180"
		)
		(pin "181"
		)
		(pin "182"
		)
		(pin "183"
		)
		(pin "184"
		)
		(pin "185"
		)
		(pin "186"
		)
		(pin "187"
		)
		(pin "188"
		)
		(pin "189"
		)
		(pin "190"
		)
		(pin "191"
		)
		(pin "192"
		)
		(pin "193"
		)
		(pin "194"
		)
		(pin "195"
		)
		(pin "196"
		)
		(pin "197"
		)
		(pin "198"
		)
		(pin "199"
		)
		(pin "200"
		)
		(pin "201"
		)
		(pin "202"
		)
		(pin "203"
		)
		(pin "204"
		)
		(pin "205"
		)
		(pin "206"
		)
		(pin "207"
		)
		(pin "208"
		)
		(pin "209"
		)
		(pin "210"
		)
		(pin "211"
		)
		(pin "212"
		)
		(pin "213"
		)
		(pin "214"
		)
		(pin "215"
		)
		(pin "216"
		)
		(pin "217"
		)
		(pin "218"
		)
		(pin "219"
		)
		(pin "220"
		)
		(pin "221"
		)
		(pin "222"
		)
		(pin "223"
		)
		(pin "224"
		)
		(pin "225"
		)
		(pin "226"
		)
		(pin "227"
		)
		(pin "228"
		)
		(pin "229"
		)
		(pin "230"
		)
		(pin "231"
		)
		(pin "232"
		)
		(pin "233"
		)
		(pin "234"
		)
		(pin "235"
		)
		(pin "236"
		)
		(pin "237"
		)
		(pin "238"
		)
		(pin "239"
		)
		(pin "240"
		)
		(pin "241"
		)
		(pin "242"
		)
		(pin "243"
		)
		(pin "244"
		)
		(pin "245"
		)
		(pin "246"
		)
		(pin "247"
		)
		(pin "248"
		)
		(pin "249"
		)
		(pin "250"
		)
		(pin "251"
		)
		(pin "252"
		)
		(pin "253"
		)
		(pin "254"
		)
		(pin "255"
		)
		(instances
			(project "lpddr4-test-board"
				(path ""
					(reference "J9")
					(unit 1)
				)
			)
		)
	)
	(symbol
		(lib_id "antmicroMemoryConnectorsPCCardSockets:Bus_DDR4_SODIMM_TE_2309409")
		(at 262.89 52.705 0)
		(unit 2)
		(exclude_from_sim no)
		(in_bom yes)
		(on_board yes)
		(dnp no)
		(property "Reference" "J9"
			(at 266.7 48.26 0)
			(effects
				(font
					(size 1.27 1.27)
				)
				(justify left bottom)
			)
		)
		(property "Value" "Bus_DDR4_SODIMM_TE_2309409"
			(at 299.72 60.325 0)
			(effects
				(font
					(size 1.27 1.27)
					(thickness 0.15)
				)
				(justify left bottom)
				(hide yes)
			)
		)
		(property "Footprint" "antmicro-footprints:Bus_DDR4_SODIMM_TE_2309409"
			(at 299.72 62.865 0)
			(effects
				(font
					(size 1.27 1.27)
					(thickness 0.15)
				)
				(justify left bottom)
				(hide yes)
			)
		)
		(property "Datasheet" "https://www.mouser.com/datasheet/2/418/7/ENG_CD_2309409_5-2032664.pdf"
			(at 299.72 65.405 0)
			(effects
				(font
					(size 1.27 1.27)
					(thickness 0.15)
				)
				(justify left bottom)
				(hide yes)
			)
		)
		(property "Description" ""
			(at 262.89 52.705 0)
			(effects
				(font
					(size 1.27 1.27)
				)
			)
		)
		(property "MPN" "2309409-1"
			(at 266.7 220.98 0)
			(effects
				(font
					(size 1.27 1.27)
					(thickness 0.15)
				)
				(justify left bottom)
			)
		)
		(property "Manufacturer" "TE Connectivity"
			(at 299.72 67.945 0)
			(effects
				(font
					(size 1.27 1.27)
					(thickness 0.15)
				)
				(justify left bottom)
				(hide yes)
			)
		)
		(property "Author" "Antmicro"
			(at 299.72 70.485 0)
			(effects
				(font
					(size 1.27 1.27)
					(thickness 0.15)
				)
				(justify left bottom)
				(hide yes)
			)
		)
		(property "License" "Apache-2.0"
			(at 299.72 73.025 0)
			(effects
				(font
					(size 1.27 1.27)
					(thickness 0.15)
				)
				(justify left bottom)
				(hide yes)
			)
		)
		(pin "131"
		)
		(pin "132"
		)
		(pin "133"
		)
		(pin "134"
		)
		(pin "135"
		)
		(pin "136"
		)
		(pin "137"
		)
		(pin "138"
		)
		(pin "139"
		)
		(pin "140"
		)
		(pin "141"
		)
		(pin "142"
		)
		(pin "143"
		)
		(pin "144"
		)
		(pin "145"
		)
		(pin "146"
		)
		(pin "147"
		)
		(pin "148"
		)
		(pin "149"
		)
		(pin "150"
		)
		(pin "151"
		)
		(pin "152"
		)
		(pin "153"
		)
		(pin "154"
		)
		(pin "155"
		)
		(pin "156"
		)
		(pin "157"
		)
		(pin "158"
		)
		(pin "159"
		)
		(pin "160"
		)
		(pin "161"
		)
		(pin "162"
		)
		(pin "163"
		)
		(pin "164"
		)
		(pin "165"
		)
		(pin "166"
		)
		(pin "167"
		)
		(pin "168"
		)
		(pin "169"
		)
		(pin "170"
		)
		(pin "171"
		)
		(pin "172"
		)
		(pin "173"
		)
		(pin "174"
		)
		(pin "175"
		)
		(pin "176"
		)
		(pin "177"
		)
		(pin "178"
		)
		(pin "179"
		)
		(pin "180"
		)
		(pin "181"
		)
		(pin "182"
		)
		(pin "183"
		)
		(pin "184"
		)
		(pin "185"
		)
		(pin "186"
		)
		(pin "187"
		)
		(pin "188"
		)
		(pin "189"
		)
		(pin "190"
		)
		(pin "191"
		)
		(pin "192"
		)
		(pin "193"
		)
		(pin "194"
		)
		(pin "195"
		)
		(pin "196"
		)
		(pin "197"
		)
		(pin "198"
		)
		(pin "199"
		)
		(pin "200"
		)
		(pin "201"
		)
		(pin "202"
		)
		(pin "203"
		)
		(pin "204"
		)
		(pin "205"
		)
		(pin "206"
		)
		(pin "207"
		)
		(pin "208"
		)
		(pin "209"
		)
		(pin "210"
		)
		(pin "211"
		)
		(pin "212"
		)
		(pin "213"
		)
		(pin "214"
		)
		(pin "215"
		)
		(pin "216"
		)
		(pin "217"
		)
		(pin "218"
		)
		(pin "219"
		)
		(pin "220"
		)
		(pin "221"
		)
		(pin "222"
		)
		(pin "223"
		)
		(pin "224"
		)
		(pin "225"
		)
		(pin "226"
		)
		(pin "227"
		)
		(pin "228"
		)
		(pin "229"
		)
		(pin "230"
		)
		(pin "231"
		)
		(pin "232"
		)
		(pin "233"
		)
		(pin "234"
		)
		(pin "235"
		)
		(pin "236"
		)
		(pin "237"
		)
		(pin "238"
		)
		(pin "239"
		)
		(pin "240"
		)
		(pin "241"
		)
		(pin "242"
		)
		(pin "243"
		)
		(pin "244"
		)
		(pin "245"
		)
		(pin "246"
		)
		(pin "247"
		)
		(pin "248"
		)
		(pin "249"
		)
		(pin "250"
		)
		(pin "251"
		)
		(pin "252"
		)
		(pin "253"
		)
		(pin "254"
		)
		(pin "255"
		)
		(pin "256"
		)
		(pin "257"
		)
		(pin "258"
		)
		(pin "259"
		)
		(pin "260"
		)
		(pin "12"
		)
		(pin "1"
		)
		(pin "10"
		)
		(pin "100"
		)
		(pin "101"
		)
		(pin "102"
		)
		(pin "103"
		)
		(pin "104"
		)
		(pin "105"
		)
		(pin "106"
		)
		(pin "107"
		)
		(pin "108"
		)
		(pin "109"
		)
		(pin "11"
		)
		(pin "110"
		)
		(pin "111"
		)
		(pin "112"
		)
		(pin "113"
		)
		(pin "114"
		)
		(pin "115"
		)
		(pin "116"
		)
		(pin "117"
		)
		(pin "118"
		)
		(pin "119"
		)
		(pin "120"
		)
		(pin "121"
		)
		(pin "122"
		)
		(pin "123"
		)
		(pin "124"
		)
		(pin "125"
		)
		(pin "126"
		)
		(pin "127"
		)
		(pin "128"
		)
		(pin "129"
		)
		(pin "13"
		)
		(pin "130"
		)
		(pin "14"
		)
		(pin "15"
		)
		(pin "16"
		)
		(pin "17"
		)
		(pin "18"
		)
		(pin "19"
		)
		(pin "2"
		)
		(pin "20"
		)
		(pin "21"
		)
		(pin "22"
		)
		(pin "23"
		)
		(pin "24"
		)
		(pin "25"
		)
		(pin "26"
		)
		(pin "27"
		)
		(pin "28"
		)
		(pin "29"
		)
		(pin "3"
		)
		(pin "30"
		)
		(pin "31"
		)
		(pin "32"
		)
		(pin "33"
		)
		(pin "34"
		)
		(pin "35"
		)
		(pin "36"
		)
		(pin "37"
		)
		(pin "38"
		)
		(pin "39"
		)
		(pin "4"
		)
		(pin "40"
		)
		(pin "41"
		)
		(pin "42"
		)
		(pin "43"
		)
		(pin "44"
		)
		(pin "45"
		)
		(pin "46"
		)
		(pin "47"
		)
		(pin "48"
		)
		(pin "49"
		)
		(pin "5"
		)
		(pin "50"
		)
		(pin "51"
		)
		(pin "52"
		)
		(pin "53"
		)
		(pin "54"
		)
		(pin "55"
		)
		(pin "56"
		)
		(pin "57"
		)
		(pin "58"
		)
		(pin "59"
		)
		(pin "6"
		)
		(pin "60"
		)
		(pin "61"
		)
		(pin "62"
		)
		(pin "63"
		)
		(pin "64"
		)
		(pin "65"
		)
		(pin "66"
		)
		(pin "67"
		)
		(pin "68"
		)
		(pin "69"
		)
		(pin "7"
		)
		(pin "70"
		)
		(pin "71"
		)
		(pin "72"
		)
		(pin "73"
		)
		(pin "74"
		)
		(pin "75"
		)
		(pin "76"
		)
		(pin "77"
		)
		(pin "78"
		)
		(pin "79"
		)
		(pin "8"
		)
		(pin "80"
		)
		(pin "81"
		)
		(pin "82"
		)
		(pin "83"
		)
		(pin "84"
		)
		(pin "85"
		)
		(pin "86"
		)
		(pin "87"
		)
		(pin "88"
		)
		(pin "89"
		)
		(pin "9"
		)
		(pin "90"
		)
		(pin "91"
		)
		(pin "92"
		)
		(pin "93"
		)
		(pin "94"
		)
		(pin "95"
		)
		(pin "96"
		)
		(pin "97"
		)
		(pin "98"
		)
		(pin "99"
		)
		(pin "S1"
		)
		(pin "S2"
		)
		(instances
			(project "lpddr4-test-board"
				(path ""
					(reference "J9")
					(unit 2)
				)
			)
		)
	)
	(symbol
		(lib_id "antmicropower:GND")
		(at 287.655 217.805 0)
		(unit 1)
		(exclude_from_sim no)
		(in_bom yes)
		(on_board yes)
		(dnp no)
		(property "Reference" "#PWR0227"
			(at 287.655 224.155 0)
			(effects
				(font
					(size 1.27 1.27)
				)
				(justify left bottom)
				(hide yes)
			)
		)
		(property "Value" "GND"
			(at 287.782 222.1992 0)
			(effects
				(font
					(size 1.27 1.27)
				)
				(justify left bottom)
			)
		)
		(property "Footprint" ""
			(at 287.655 217.805 0)
			(effects
				(font
					(size 1.27 1.27)
				)
				(justify left bottom)
				(hide yes)
			)
		)
		(property "Datasheet" ""
			(at 287.655 217.805 0)
			(effects
				(font
					(size 1.27 1.27)
				)
				(justify left bottom)
				(hide yes)
			)
		)
		(property "Description" ""
			(at 287.655 217.805 0)
			(effects
				(font
					(size 1.27 1.27)
				)
			)
		)
		(pin "1"
		)
		(instances
			(project "lpddr4-test-board"
				(path ""
					(reference "#PWR0227")
					(unit 1)
				)
			)
		)
	)
	(symbol
		(lib_id "antmicropower:GND")
		(at 254 217.805 0)
		(unit 1)
		(exclude_from_sim no)
		(in_bom yes)
		(on_board yes)
		(dnp no)
		(property "Reference" "#PWR0226"
			(at 254 224.155 0)
			(effects
				(font
					(size 1.27 1.27)
				)
				(justify left bottom)
				(hide yes)
			)
		)
		(property "Value" "GND"
			(at 254.127 222.1992 0)
			(effects
				(font
					(size 1.27 1.27)
				)
				(justify left bottom)
			)
		)
		(property "Footprint" ""
			(at 254 217.805 0)
			(effects
				(font
					(size 1.27 1.27)
				)
				(justify left bottom)
				(hide yes)
			)
		)
		(property "Datasheet" ""
			(at 254 217.805 0)
			(effects
				(font
					(size 1.27 1.27)
				)
				(justify left bottom)
				(hide yes)
			)
		)
		(property "Description" ""
			(at 254 217.805 0)
			(effects
				(font
					(size 1.27 1.27)
				)
			)
		)
		(pin "1"
		)
		(instances
			(project "lpddr4-test-board"
				(path ""
					(reference "#PWR0226")
					(unit 1)
				)
			)
		)
	)
	(symbol
		(lib_id "antmicroMechanicalParts:Spacer_Drill3.7mm_H5mm_9774050151R")
		(at 33.02 240.665 0)
		(unit 1)
		(exclude_from_sim no)
		(in_bom yes)
		(on_board yes)
		(dnp no)
		(property "Reference" "SP1"
			(at 35.56 235.585 0)
			(effects
				(font
					(size 1.27 1.27)
				)
				(justify left bottom)
			)
		)
		(property "Value" "Spacer_H5.0mm_9774050151"
			(at 35.56 237.49 0)
			(effects
				(font
					(size 1.27 1.27)
					(thickness 0.15)
				)
				(justify left bottom)
			)
		)
		(property "Footprint" "antmicro-footprints:Spacer_Drill3.7mm_H5mm_9774050151R"
			(at 55.88 248.285 0)
			(effects
				(font
					(size 1.27 1.27)
					(thickness 0.15)
				)
				(justify left bottom)
				(hide yes)
			)
		)
		(property "Datasheet" "https://www.we-online.com/catalog/datasheet/9774050151.pdf"
			(at 55.88 250.825 0)
			(effects
				(font
					(size 1.27 1.27)
					(thickness 0.15)
				)
				(justify left bottom)
				(hide yes)
			)
		)
		(property "Description" ""
			(at 33.02 240.665 0)
			(effects
				(font
					(size 1.27 1.27)
				)
			)
		)
		(property "Manufacturer" "Würth Elektronik"
			(at 55.88 253.365 0)
			(effects
				(font
					(size 1.27 1.27)
					(thickness 0.15)
				)
				(justify left bottom)
				(hide yes)
			)
		)
		(property "MPN" "9774050151R"
			(at 55.88 255.905 0)
			(effects
				(font
					(size 1.27 1.27)
					(thickness 0.15)
				)
				(justify left bottom)
				(hide yes)
			)
		)
		(property "Author" "Antmicro"
			(at 55.88 258.445 0)
			(effects
				(font
					(size 1.27 1.27)
					(thickness 0.15)
				)
				(justify left bottom)
				(hide yes)
			)
		)
		(property "License" "Apache-2.0"
			(at 55.88 260.985 0)
			(effects
				(font
					(size 1.27 1.27)
					(thickness 0.15)
				)
				(justify left bottom)
				(hide yes)
			)
		)
		(pin "1"
		)
		(instances
			(project "lpddr4-test-board"
				(path ""
					(reference "SP1")
					(unit 1)
				)
			)
		)
	)
	(symbol
		(lib_id "antmicropower:GND")
		(at 205.74 113.03 0)
		(unit 1)
		(exclude_from_sim no)
		(in_bom yes)
		(on_board yes)
		(dnp no)
		(property "Reference" "#PWR0225"
			(at 205.74 119.38 0)
			(effects
				(font
					(size 1.27 1.27)
				)
				(justify left bottom)
				(hide yes)
			)
		)
		(property "Value" "GND"
			(at 205.867 117.4242 0)
			(effects
				(font
					(size 1.27 1.27)
				)
				(justify left bottom)
			)
		)
		(property "Footprint" ""
			(at 205.74 113.03 0)
			(effects
				(font
					(size 1.27 1.27)
				)
				(justify left bottom)
				(hide yes)
			)
		)
		(property "Datasheet" ""
			(at 205.74 113.03 0)
			(effects
				(font
					(size 1.27 1.27)
				)
				(justify left bottom)
				(hide yes)
			)
		)
		(property "Description" ""
			(at 205.74 113.03 0)
			(effects
				(font
					(size 1.27 1.27)
				)
			)
		)
		(pin "1"
		)
		(instances
			(project "lpddr4-test-board"
				(path ""
					(reference "#PWR0225")
					(unit 1)
				)
			)
		)
	)
	(symbol
		(lib_id "antmicropower:GND")
		(at 202.565 220.98 0)
		(unit 1)
		(exclude_from_sim no)
		(in_bom yes)
		(on_board yes)
		(dnp no)
		(property "Reference" "#PWR0224"
			(at 202.565 227.33 0)
			(effects
				(font
					(size 1.27 1.27)
				)
				(justify left bottom)
				(hide yes)
			)
		)
		(property "Value" "GND"
			(at 202.692 225.3742 0)
			(effects
				(font
					(size 1.27 1.27)
				)
				(justify left bottom)
			)
		)
		(property "Footprint" ""
			(at 202.565 220.98 0)
			(effects
				(font
					(size 1.27 1.27)
				)
				(justify left bottom)
				(hide yes)
			)
		)
		(property "Datasheet" ""
			(at 202.565 220.98 0)
			(effects
				(font
					(size 1.27 1.27)
				)
				(justify left bottom)
				(hide yes)
			)
		)
		(property "Description" ""
			(at 202.565 220.98 0)
			(effects
				(font
					(size 1.27 1.27)
				)
			)
		)
		(pin "1"
		)
		(instances
			(project "lpddr4-test-board"
				(path ""
					(reference "#PWR0224")
					(unit 1)
				)
			)
		)
	)
	(symbol
		(lib_id "antmicroModules:ddr5-testbed")
		(at 34.925 219.075 0)
		(unit 1)
		(exclude_from_sim no)
		(in_bom no)
		(on_board yes)
		(dnp yes)
		(property "Reference" "M1"
			(at 27.305 213.995 0)
			(effects
				(font
					(size 1.27 1.27)
				)
				(justify left bottom)
			)
		)
		(property "Value" "ddr5-testbed"
			(at 28.575 220.345 0)
			(effects
				(font
					(size 1.27 1.27)
					(thickness 0.15)
				)
				(justify left bottom)
			)
		)
		(property "Footprint" "antmicro-footprints:DDR5-testbed"
			(at 57.785 226.695 0)
			(effects
				(font
					(size 1.27 1.27)
					(thickness 0.15)
				)
				(justify left bottom)
				(hide yes)
			)
		)
		(property "Datasheet" ""
			(at 57.785 229.235 0)
			(effects
				(font
					(size 1.27 1.27)
					(thickness 0.15)
				)
				(justify left bottom)
				(hide yes)
			)
		)
		(property "Description" ""
			(at 34.925 219.075 0)
			(effects
				(font
					(size 1.27 1.27)
				)
			)
		)
		(property "MPN" ""
			(at 57.785 221.615 0)
			(effects
				(font
					(size 1.27 1.27)
					(thickness 0.15)
				)
				(justify left bottom)
			)
		)
		(property "Manufacturer" "Antmicro "
			(at 57.785 231.775 0)
			(effects
				(font
					(size 1.27 1.27)
					(thickness 0.15)
				)
				(justify left bottom)
				(hide yes)
			)
		)
		(property "Author" "Antmicro"
			(at 57.785 234.315 0)
			(effects
				(font
					(size 1.27 1.27)
					(thickness 0.15)
				)
				(justify left bottom)
				(hide yes)
			)
		)
		(property "License" "Apache-2.0"
			(at 57.785 236.855 0)
			(effects
				(font
					(size 1.27 1.27)
					(thickness 0.15)
				)
				(justify left bottom)
				(hide yes)
			)
		)
		(instances
			(project "lpddr4-test-board"
				(path ""
					(reference "M1")
					(unit 1)
				)
			)
		)
	)
)
